FILE_TYPE = MACRO_DRAWING;
SET COLOR_WIRE YELLOW;
SET COLOR_PROP MONO;
SET COLOR_DOT WHITE;
SET COLOR_ARC YELLOW;
SET COLOR_BODY GREEN;
SET COLOR_NOTE MONO;
SET PROP_DISPLAY VALUE;
SET PAGE_NUMBER P26;
FORCEADD OFFPAGE..5
(-6350 525);
FORCEPROP 2 LAST $XR1 50 
J 0
(-6664 525);
DISPLAY 0.638298 (-6664 525);
PAINT MONO (-6664 525);
FORCEPROP 2 LAST $XR0 49 
J 0
(-6574 525);
DISPLAY 0.638298 (-6574 525);
PAINT MONO (-6574 525);
FORCEPROP 2 LAST CDS_LIB mstr_standard
J 0
(-6350 525);
PAINT MONO (-6350 525);
DISPLAY INVISIBLE (-6350 525);
FORCEPROP 1 LAST OFFPAGE TRUE
J 0
(-6025 400);
DISPLAY 1.170213 (-6025 400);
PAINT GREEN (-6025 400);
DISPLAY INVISIBLE (-6025 400);
FORCEPROP 1 LAST COMMENT_BODY TRUE
J 0
(-6250 450);
DISPLAY 1.170213 (-6250 450);
PAINT GREEN (-6250 450);
DISPLAY INVISIBLE (-6250 450);
FORCEPROP 2 LAST PATH I1
J 0
(-6300 600);
DISPLAY 1.021277 (-6300 600);
PAINT ORANGE (-6300 600);
DISPLAY INVISIBLE (-6300 600);
FORCEADD TAP..6
(-5500 875);
FORCEPROP 3 LASTPIN (-5450 875) SIG_NAME M_D_CLK_DP<1>
J 0
(-5440 885);
DISPLAY 0.659574 (-5440 885);
PAINT MONO (-5440 885);
DISPLAY INVISIBLE (-5440 885);
FORCEPROP 1 LASTPIN (-5450 875) BN 1
J 0
(-5502 883);
DISPLAY 0.617021 (-5502 883);
PAINT PINK (-5502 883);
FORCEPROP 2 LAST CDS_LIB mstr_standard
J 0
(-5500 875);
PAINT MONO (-5500 875);
DISPLAY INVISIBLE (-5500 875);
FORCEPROP 1 LAST BODY_TYPE PLUMBING
J 0
(-5500 825);
DISPLAY 1.595745 (-5500 825);
PAINT GREEN (-5500 825);
DISPLAY INVISIBLE (-5500 825);
FORCEPROP 1 LAST HDL_TAP TRUE
J 0
(-5175 750);
DISPLAY 1.595745 (-5175 750);
PAINT GREEN (-5175 750);
DISPLAY INVISIBLE (-5175 750);
FORCEPROP 1 LAST PATH I10
J 0
(-5502 875);
DISPLAY 0.872340 (-5502 875);
PAINT GREEN (-5502 875);
DISPLAY INVISIBLE (-5502 875);
FORCEADD TAP..6
R 2
(-2775 1525);
FORCEPROP 3 LASTPIN (-2825 1525) SIG_NAME M_D_ODT<2>
J 0
(-2815 1535);
DISPLAY 0.659574 (-2815 1535);
PAINT MONO (-2815 1535);
DISPLAY INVISIBLE (-2815 1535);
FORCEPROP 1 LASTPIN (-2825 1525) BN 2
J 2
(-2773 1533);
DISPLAY 0.617021 (-2773 1533);
PAINT PINK (-2773 1533);
FORCEPROP 2 LAST CDS_LIB mstr_standard
J 0
(-2775 1525);
PAINT MONO (-2775 1525);
DISPLAY INVISIBLE (-2775 1525);
FORCEPROP 1 LAST BODY_TYPE PLUMBING
J 2
(-2775 1475);
DISPLAY 1.595745 (-2775 1475);
PAINT GREEN (-2775 1475);
DISPLAY INVISIBLE (-2775 1475);
FORCEPROP 1 LAST HDL_TAP TRUE
J 2
(-3100 1400);
DISPLAY 1.595745 (-3100 1400);
PAINT GREEN (-3100 1400);
DISPLAY INVISIBLE (-3100 1400);
FORCEPROP 1 LAST PATH I100
J 2
(-2773 1525);
DISPLAY 0.872340 (-2773 1525);
PAINT GREEN (-2773 1525);
DISPLAY INVISIBLE (-2773 1525);
FORCEADD TAP..6
R 2
(-2775 1575);
FORCEPROP 3 LASTPIN (-2825 1575) SIG_NAME M_D_ODT<3>
J 0
(-2815 1585);
DISPLAY 0.659574 (-2815 1585);
PAINT MONO (-2815 1585);
DISPLAY INVISIBLE (-2815 1585);
FORCEPROP 1 LASTPIN (-2825 1575) BN 3
J 2
(-2773 1583);
DISPLAY 0.617021 (-2773 1583);
PAINT PINK (-2773 1583);
FORCEPROP 2 LAST CDS_LIB mstr_standard
J 0
(-2775 1575);
PAINT MONO (-2775 1575);
DISPLAY INVISIBLE (-2775 1575);
FORCEPROP 1 LAST BODY_TYPE PLUMBING
J 2
(-2775 1525);
DISPLAY 1.595745 (-2775 1525);
PAINT GREEN (-2775 1525);
DISPLAY INVISIBLE (-2775 1525);
FORCEPROP 1 LAST HDL_TAP TRUE
J 2
(-3100 1450);
DISPLAY 1.595745 (-3100 1450);
PAINT GREEN (-3100 1450);
DISPLAY INVISIBLE (-3100 1450);
FORCEPROP 1 LAST PATH I101
J 2
(-2773 1575);
DISPLAY 0.872340 (-2773 1575);
PAINT GREEN (-2773 1575);
DISPLAY INVISIBLE (-2773 1575);
FORCEADD TAP..6
R 2
(-2775 1475);
FORCEPROP 3 LASTPIN (-2825 1475) SIG_NAME M_D_ODT<1>
J 0
(-2815 1485);
DISPLAY 0.659574 (-2815 1485);
PAINT MONO (-2815 1485);
DISPLAY INVISIBLE (-2815 1485);
FORCEPROP 1 LASTPIN (-2825 1475) BN 1
J 2
(-2773 1483);
DISPLAY 0.617021 (-2773 1483);
PAINT PINK (-2773 1483);
FORCEPROP 2 LAST CDS_LIB mstr_standard
J 0
(-2775 1475);
PAINT MONO (-2775 1475);
DISPLAY INVISIBLE (-2775 1475);
FORCEPROP 1 LAST BODY_TYPE PLUMBING
J 2
(-2775 1425);
DISPLAY 1.595745 (-2775 1425);
PAINT GREEN (-2775 1425);
DISPLAY INVISIBLE (-2775 1425);
FORCEPROP 1 LAST HDL_TAP TRUE
J 2
(-3100 1350);
DISPLAY 1.595745 (-3100 1350);
PAINT GREEN (-3100 1350);
DISPLAY INVISIBLE (-3100 1350);
FORCEPROP 1 LAST PATH I102
J 2
(-2773 1475);
DISPLAY 0.872340 (-2773 1475);
PAINT GREEN (-2773 1475);
DISPLAY INVISIBLE (-2773 1475);
FORCEADD TAP..6
R 2
(-2775 1675);
FORCEPROP 3 LASTPIN (-2825 1675) SIG_NAME M_D_CKE<0>
J 0
(-2815 1685);
DISPLAY 0.659574 (-2815 1685);
PAINT MONO (-2815 1685);
DISPLAY INVISIBLE (-2815 1685);
FORCEPROP 1 LASTPIN (-2825 1675) BN 0
J 2
(-2773 1683);
DISPLAY 0.617021 (-2773 1683);
PAINT PINK (-2773 1683);
FORCEPROP 2 LAST CDS_LIB mstr_standard
J 0
(-2775 1675);
PAINT MONO (-2775 1675);
DISPLAY INVISIBLE (-2775 1675);
FORCEPROP 1 LAST BODY_TYPE PLUMBING
J 2
(-2775 1625);
DISPLAY 1.595745 (-2775 1625);
PAINT GREEN (-2775 1625);
DISPLAY INVISIBLE (-2775 1625);
FORCEPROP 1 LAST HDL_TAP TRUE
J 2
(-3100 1550);
DISPLAY 1.595745 (-3100 1550);
PAINT GREEN (-3100 1550);
DISPLAY INVISIBLE (-3100 1550);
FORCEPROP 1 LAST PATH I103
J 2
(-2773 1675);
DISPLAY 0.872340 (-2773 1675);
PAINT GREEN (-2773 1675);
DISPLAY INVISIBLE (-2773 1675);
FORCEADD TAP..6
R 2
(-2775 1725);
FORCEPROP 3 LASTPIN (-2825 1725) SIG_NAME M_D_CKE<1>
J 0
(-2815 1735);
DISPLAY 0.659574 (-2815 1735);
PAINT MONO (-2815 1735);
DISPLAY INVISIBLE (-2815 1735);
FORCEPROP 1 LASTPIN (-2825 1725) BN 1
J 2
(-2773 1733);
DISPLAY 0.617021 (-2773 1733);
PAINT PINK (-2773 1733);
FORCEPROP 2 LAST CDS_LIB mstr_standard
J 0
(-2775 1725);
PAINT MONO (-2775 1725);
DISPLAY INVISIBLE (-2775 1725);
FORCEPROP 1 LAST BODY_TYPE PLUMBING
J 2
(-2775 1675);
DISPLAY 1.595745 (-2775 1675);
PAINT GREEN (-2775 1675);
DISPLAY INVISIBLE (-2775 1675);
FORCEPROP 1 LAST HDL_TAP TRUE
J 2
(-3100 1600);
DISPLAY 1.595745 (-3100 1600);
PAINT GREEN (-3100 1600);
DISPLAY INVISIBLE (-3100 1600);
FORCEPROP 1 LAST PATH I104
J 2
(-2773 1725);
DISPLAY 0.872340 (-2773 1725);
PAINT GREEN (-2773 1725);
DISPLAY INVISIBLE (-2773 1725);
FORCEADD TAP..6
R 2
(-2775 1775);
FORCEPROP 3 LASTPIN (-2825 1775) SIG_NAME M_D_CKE<2>
J 0
(-2815 1785);
DISPLAY 0.659574 (-2815 1785);
PAINT MONO (-2815 1785);
DISPLAY INVISIBLE (-2815 1785);
FORCEPROP 1 LASTPIN (-2825 1775) BN 2
J 2
(-2773 1783);
DISPLAY 0.617021 (-2773 1783);
PAINT PINK (-2773 1783);
FORCEPROP 2 LAST CDS_LIB mstr_standard
J 0
(-2775 1775);
PAINT MONO (-2775 1775);
DISPLAY INVISIBLE (-2775 1775);
FORCEPROP 1 LAST BODY_TYPE PLUMBING
J 2
(-2775 1725);
DISPLAY 1.595745 (-2775 1725);
PAINT GREEN (-2775 1725);
DISPLAY INVISIBLE (-2775 1725);
FORCEPROP 1 LAST HDL_TAP TRUE
J 2
(-3100 1650);
DISPLAY 1.595745 (-3100 1650);
PAINT GREEN (-3100 1650);
DISPLAY INVISIBLE (-3100 1650);
FORCEPROP 1 LAST PATH I105
J 2
(-2773 1775);
DISPLAY 0.872340 (-2773 1775);
PAINT GREEN (-2773 1775);
DISPLAY INVISIBLE (-2773 1775);
FORCEADD TAP..6
R 2
(-2775 1825);
FORCEPROP 3 LASTPIN (-2825 1825) SIG_NAME M_D_CKE<3>
J 0
(-2815 1835);
DISPLAY 0.659574 (-2815 1835);
PAINT MONO (-2815 1835);
DISPLAY INVISIBLE (-2815 1835);
FORCEPROP 1 LASTPIN (-2825 1825) BN 3
J 2
(-2773 1833);
DISPLAY 0.617021 (-2773 1833);
PAINT PINK (-2773 1833);
FORCEPROP 2 LAST CDS_LIB mstr_standard
J 0
(-2775 1825);
PAINT MONO (-2775 1825);
DISPLAY INVISIBLE (-2775 1825);
FORCEPROP 1 LAST BODY_TYPE PLUMBING
J 2
(-2775 1775);
DISPLAY 1.595745 (-2775 1775);
PAINT GREEN (-2775 1775);
DISPLAY INVISIBLE (-2775 1775);
FORCEPROP 1 LAST HDL_TAP TRUE
J 2
(-3100 1700);
DISPLAY 1.595745 (-3100 1700);
PAINT GREEN (-3100 1700);
DISPLAY INVISIBLE (-3100 1700);
FORCEPROP 1 LAST PATH I106
J 2
(-2773 1825);
DISPLAY 0.872340 (-2773 1825);
PAINT GREEN (-2773 1825);
DISPLAY INVISIBLE (-2773 1825);
FORCEADD TAP..6
R 2
(-2775 1925);
FORCEPROP 3 LASTPIN (-2825 1925) SIG_NAME M_D_MA<0>
J 0
(-2815 1935);
DISPLAY 0.659574 (-2815 1935);
PAINT MONO (-2815 1935);
DISPLAY INVISIBLE (-2815 1935);
FORCEPROP 1 LASTPIN (-2825 1925) BN 0
J 2
(-2773 1933);
DISPLAY 0.617021 (-2773 1933);
PAINT PINK (-2773 1933);
FORCEPROP 2 LAST CDS_LIB mstr_standard
J 0
(-2775 1925);
PAINT MONO (-2775 1925);
DISPLAY INVISIBLE (-2775 1925);
FORCEPROP 1 LAST BODY_TYPE PLUMBING
J 2
(-2775 1875);
DISPLAY 1.595745 (-2775 1875);
PAINT GREEN (-2775 1875);
DISPLAY INVISIBLE (-2775 1875);
FORCEPROP 1 LAST HDL_TAP TRUE
J 2
(-3100 1800);
DISPLAY 1.595745 (-3100 1800);
PAINT GREEN (-3100 1800);
DISPLAY INVISIBLE (-3100 1800);
FORCEPROP 1 LAST PATH I107
J 2
(-2773 1925);
DISPLAY 0.872340 (-2773 1925);
PAINT GREEN (-2773 1925);
DISPLAY INVISIBLE (-2773 1925);
FORCEADD TAP..6
R 2
(-2775 1975);
FORCEPROP 3 LASTPIN (-2825 1975) SIG_NAME M_D_MA<1>
J 0
(-2815 1985);
DISPLAY 0.659574 (-2815 1985);
PAINT MONO (-2815 1985);
DISPLAY INVISIBLE (-2815 1985);
FORCEPROP 1 LASTPIN (-2825 1975) BN 1
J 2
(-2773 1983);
DISPLAY 0.617021 (-2773 1983);
PAINT PINK (-2773 1983);
FORCEPROP 2 LAST CDS_LIB mstr_standard
J 0
(-2775 1975);
PAINT MONO (-2775 1975);
DISPLAY INVISIBLE (-2775 1975);
FORCEPROP 1 LAST BODY_TYPE PLUMBING
J 2
(-2775 1925);
DISPLAY 1.595745 (-2775 1925);
PAINT GREEN (-2775 1925);
DISPLAY INVISIBLE (-2775 1925);
FORCEPROP 1 LAST HDL_TAP TRUE
J 2
(-3100 1850);
DISPLAY 1.595745 (-3100 1850);
PAINT GREEN (-3100 1850);
DISPLAY INVISIBLE (-3100 1850);
FORCEPROP 1 LAST PATH I108
J 2
(-2773 1975);
DISPLAY 0.872340 (-2773 1975);
PAINT GREEN (-2773 1975);
DISPLAY INVISIBLE (-2773 1975);
FORCEADD TAP..6
R 2
(-2775 2075);
FORCEPROP 3 LASTPIN (-2825 2075) SIG_NAME M_D_MA<3>
J 0
(-2815 2085);
DISPLAY 0.659574 (-2815 2085);
PAINT MONO (-2815 2085);
DISPLAY INVISIBLE (-2815 2085);
FORCEPROP 1 LASTPIN (-2825 2075) BN 3
J 2
(-2773 2083);
DISPLAY 0.617021 (-2773 2083);
PAINT PINK (-2773 2083);
FORCEPROP 2 LAST CDS_LIB mstr_standard
J 0
(-2775 2075);
PAINT MONO (-2775 2075);
DISPLAY INVISIBLE (-2775 2075);
FORCEPROP 1 LAST BODY_TYPE PLUMBING
J 2
(-2775 2025);
DISPLAY 1.595745 (-2775 2025);
PAINT GREEN (-2775 2025);
DISPLAY INVISIBLE (-2775 2025);
FORCEPROP 1 LAST HDL_TAP TRUE
J 2
(-3100 1950);
DISPLAY 1.595745 (-3100 1950);
PAINT GREEN (-3100 1950);
DISPLAY INVISIBLE (-3100 1950);
FORCEPROP 1 LAST PATH I109
J 2
(-2773 2075);
DISPLAY 0.872340 (-2773 2075);
PAINT GREEN (-2773 2075);
DISPLAY INVISIBLE (-2773 2075);
FORCEADD TAP..6
(-5500 925);
FORCEPROP 3 LASTPIN (-5450 925) SIG_NAME M_D_CLK_DP<2>
J 0
(-5440 935);
DISPLAY 0.659574 (-5440 935);
PAINT MONO (-5440 935);
DISPLAY INVISIBLE (-5440 935);
FORCEPROP 1 LASTPIN (-5450 925) BN 2
J 0
(-5502 933);
DISPLAY 0.617021 (-5502 933);
PAINT PINK (-5502 933);
FORCEPROP 2 LAST CDS_LIB mstr_standard
J 0
(-5500 925);
PAINT MONO (-5500 925);
DISPLAY INVISIBLE (-5500 925);
FORCEPROP 1 LAST BODY_TYPE PLUMBING
J 0
(-5500 875);
DISPLAY 1.595745 (-5500 875);
PAINT GREEN (-5500 875);
DISPLAY INVISIBLE (-5500 875);
FORCEPROP 1 LAST HDL_TAP TRUE
J 0
(-5175 800);
DISPLAY 1.595745 (-5175 800);
PAINT GREEN (-5175 800);
DISPLAY INVISIBLE (-5175 800);
FORCEPROP 1 LAST PATH I11
J 0
(-5502 925);
DISPLAY 0.872340 (-5502 925);
PAINT GREEN (-5502 925);
DISPLAY INVISIBLE (-5502 925);
FORCEADD TAP..6
R 2
(-2775 2025);
FORCEPROP 3 LASTPIN (-2825 2025) SIG_NAME M_D_MA<2>
J 0
(-2815 2035);
DISPLAY 0.659574 (-2815 2035);
PAINT MONO (-2815 2035);
DISPLAY INVISIBLE (-2815 2035);
FORCEPROP 1 LASTPIN (-2825 2025) BN 2
J 2
(-2773 2033);
DISPLAY 0.617021 (-2773 2033);
PAINT PINK (-2773 2033);
FORCEPROP 2 LAST CDS_LIB mstr_standard
J 0
(-2775 2025);
PAINT MONO (-2775 2025);
DISPLAY INVISIBLE (-2775 2025);
FORCEPROP 1 LAST BODY_TYPE PLUMBING
J 2
(-2775 1975);
DISPLAY 1.595745 (-2775 1975);
PAINT GREEN (-2775 1975);
DISPLAY INVISIBLE (-2775 1975);
FORCEPROP 1 LAST HDL_TAP TRUE
J 2
(-3100 1900);
DISPLAY 1.595745 (-3100 1900);
PAINT GREEN (-3100 1900);
DISPLAY INVISIBLE (-3100 1900);
FORCEPROP 1 LAST PATH I110
J 2
(-2773 2025);
DISPLAY 0.872340 (-2773 2025);
PAINT GREEN (-2773 2025);
DISPLAY INVISIBLE (-2773 2025);
FORCEADD TAP..6
R 2
(-2775 2125);
FORCEPROP 3 LASTPIN (-2825 2125) SIG_NAME M_D_MA<4>
J 0
(-2815 2135);
DISPLAY 0.659574 (-2815 2135);
PAINT MONO (-2815 2135);
DISPLAY INVISIBLE (-2815 2135);
FORCEPROP 1 LASTPIN (-2825 2125) BN 4
J 2
(-2773 2133);
DISPLAY 0.617021 (-2773 2133);
PAINT PINK (-2773 2133);
FORCEPROP 2 LAST CDS_LIB mstr_standard
J 0
(-2775 2125);
PAINT MONO (-2775 2125);
DISPLAY INVISIBLE (-2775 2125);
FORCEPROP 1 LAST BODY_TYPE PLUMBING
J 2
(-2775 2075);
DISPLAY 1.595745 (-2775 2075);
PAINT GREEN (-2775 2075);
DISPLAY INVISIBLE (-2775 2075);
FORCEPROP 1 LAST HDL_TAP TRUE
J 2
(-3100 2000);
DISPLAY 1.595745 (-3100 2000);
PAINT GREEN (-3100 2000);
DISPLAY INVISIBLE (-3100 2000);
FORCEPROP 1 LAST PATH I111
J 2
(-2773 2125);
DISPLAY 0.872340 (-2773 2125);
PAINT GREEN (-2773 2125);
DISPLAY INVISIBLE (-2773 2125);
FORCEADD TAP..6
R 2
(-2775 2225);
FORCEPROP 3 LASTPIN (-2825 2225) SIG_NAME M_D_MA<6>
J 0
(-2815 2235);
DISPLAY 0.659574 (-2815 2235);
PAINT MONO (-2815 2235);
DISPLAY INVISIBLE (-2815 2235);
FORCEPROP 1 LASTPIN (-2825 2225) BN 6
J 2
(-2773 2233);
DISPLAY 0.617021 (-2773 2233);
PAINT PINK (-2773 2233);
FORCEPROP 2 LAST CDS_LIB mstr_standard
J 0
(-2775 2225);
PAINT MONO (-2775 2225);
DISPLAY INVISIBLE (-2775 2225);
FORCEPROP 1 LAST BODY_TYPE PLUMBING
J 2
(-2775 2175);
DISPLAY 1.595745 (-2775 2175);
PAINT GREEN (-2775 2175);
DISPLAY INVISIBLE (-2775 2175);
FORCEPROP 1 LAST HDL_TAP TRUE
J 2
(-3100 2100);
DISPLAY 1.595745 (-3100 2100);
PAINT GREEN (-3100 2100);
DISPLAY INVISIBLE (-3100 2100);
FORCEPROP 1 LAST PATH I112
J 2
(-2773 2225);
DISPLAY 0.872340 (-2773 2225);
PAINT GREEN (-2773 2225);
DISPLAY INVISIBLE (-2773 2225);
FORCEADD TAP..6
R 2
(-2775 2175);
FORCEPROP 3 LASTPIN (-2825 2175) SIG_NAME M_D_MA<5>
J 0
(-2815 2185);
DISPLAY 0.659574 (-2815 2185);
PAINT MONO (-2815 2185);
DISPLAY INVISIBLE (-2815 2185);
FORCEPROP 1 LASTPIN (-2825 2175) BN 5
J 2
(-2773 2183);
DISPLAY 0.617021 (-2773 2183);
PAINT PINK (-2773 2183);
FORCEPROP 2 LAST CDS_LIB mstr_standard
J 0
(-2775 2175);
PAINT MONO (-2775 2175);
DISPLAY INVISIBLE (-2775 2175);
FORCEPROP 1 LAST BODY_TYPE PLUMBING
J 2
(-2775 2125);
DISPLAY 1.595745 (-2775 2125);
PAINT GREEN (-2775 2125);
DISPLAY INVISIBLE (-2775 2125);
FORCEPROP 1 LAST HDL_TAP TRUE
J 2
(-3100 2050);
DISPLAY 1.595745 (-3100 2050);
PAINT GREEN (-3100 2050);
DISPLAY INVISIBLE (-3100 2050);
FORCEPROP 1 LAST PATH I113
J 2
(-2773 2175);
DISPLAY 0.872340 (-2773 2175);
PAINT GREEN (-2773 2175);
DISPLAY INVISIBLE (-2773 2175);
FORCEADD TAP..6
R 2
(-2775 2275);
FORCEPROP 3 LASTPIN (-2825 2275) SIG_NAME M_D_MA<7>
J 0
(-2815 2285);
DISPLAY 0.659574 (-2815 2285);
PAINT MONO (-2815 2285);
DISPLAY INVISIBLE (-2815 2285);
FORCEPROP 1 LASTPIN (-2825 2275) BN 7
J 2
(-2773 2283);
DISPLAY 0.617021 (-2773 2283);
PAINT PINK (-2773 2283);
FORCEPROP 2 LAST CDS_LIB mstr_standard
J 0
(-2775 2275);
PAINT MONO (-2775 2275);
DISPLAY INVISIBLE (-2775 2275);
FORCEPROP 1 LAST BODY_TYPE PLUMBING
J 2
(-2775 2225);
DISPLAY 1.595745 (-2775 2225);
PAINT GREEN (-2775 2225);
DISPLAY INVISIBLE (-2775 2225);
FORCEPROP 1 LAST HDL_TAP TRUE
J 2
(-3100 2150);
DISPLAY 1.595745 (-3100 2150);
PAINT GREEN (-3100 2150);
DISPLAY INVISIBLE (-3100 2150);
FORCEPROP 1 LAST PATH I114
J 2
(-2773 2275);
DISPLAY 0.872340 (-2773 2275);
PAINT GREEN (-2773 2275);
DISPLAY INVISIBLE (-2773 2275);
FORCEADD TAP..6
R 2
(-2775 2325);
FORCEPROP 3 LASTPIN (-2825 2325) SIG_NAME M_D_MA<8>
J 0
(-2815 2335);
DISPLAY 0.659574 (-2815 2335);
PAINT MONO (-2815 2335);
DISPLAY INVISIBLE (-2815 2335);
FORCEPROP 1 LASTPIN (-2825 2325) BN 8
J 2
(-2773 2333);
DISPLAY 0.617021 (-2773 2333);
PAINT PINK (-2773 2333);
FORCEPROP 2 LAST CDS_LIB mstr_standard
J 0
(-2775 2325);
PAINT MONO (-2775 2325);
DISPLAY INVISIBLE (-2775 2325);
FORCEPROP 1 LAST BODY_TYPE PLUMBING
J 2
(-2775 2275);
DISPLAY 1.595745 (-2775 2275);
PAINT GREEN (-2775 2275);
DISPLAY INVISIBLE (-2775 2275);
FORCEPROP 1 LAST HDL_TAP TRUE
J 2
(-3100 2200);
DISPLAY 1.595745 (-3100 2200);
PAINT GREEN (-3100 2200);
DISPLAY INVISIBLE (-3100 2200);
FORCEPROP 1 LAST PATH I115
J 2
(-2773 2325);
DISPLAY 0.872340 (-2773 2325);
PAINT GREEN (-2773 2325);
DISPLAY INVISIBLE (-2773 2325);
FORCEADD TAP..6
R 2
(-2775 2375);
FORCEPROP 3 LASTPIN (-2825 2375) SIG_NAME M_D_MA<9>
J 0
(-2815 2385);
DISPLAY 0.659574 (-2815 2385);
PAINT MONO (-2815 2385);
DISPLAY INVISIBLE (-2815 2385);
FORCEPROP 1 LASTPIN (-2825 2375) BN 9
J 2
(-2773 2383);
DISPLAY 0.617021 (-2773 2383);
PAINT PINK (-2773 2383);
FORCEPROP 2 LAST CDS_LIB mstr_standard
J 0
(-2775 2375);
PAINT MONO (-2775 2375);
DISPLAY INVISIBLE (-2775 2375);
FORCEPROP 1 LAST BODY_TYPE PLUMBING
J 2
(-2775 2325);
DISPLAY 1.595745 (-2775 2325);
PAINT GREEN (-2775 2325);
DISPLAY INVISIBLE (-2775 2325);
FORCEPROP 1 LAST HDL_TAP TRUE
J 2
(-3100 2250);
DISPLAY 1.595745 (-3100 2250);
PAINT GREEN (-3100 2250);
DISPLAY INVISIBLE (-3100 2250);
FORCEPROP 1 LAST PATH I116
J 2
(-2773 2375);
DISPLAY 0.872340 (-2773 2375);
PAINT GREEN (-2773 2375);
DISPLAY INVISIBLE (-2773 2375);
FORCEADD TAP..6
R 2
(-2775 2425);
FORCEPROP 3 LASTPIN (-2825 2425) SIG_NAME M_D_MA<10>
J 0
(-2815 2435);
DISPLAY 0.659574 (-2815 2435);
PAINT MONO (-2815 2435);
DISPLAY INVISIBLE (-2815 2435);
FORCEPROP 1 LASTPIN (-2825 2425) BN 10
J 2
(-2773 2433);
DISPLAY 0.617021 (-2773 2433);
PAINT PINK (-2773 2433);
FORCEPROP 2 LAST CDS_LIB mstr_standard
J 0
(-2775 2425);
PAINT MONO (-2775 2425);
DISPLAY INVISIBLE (-2775 2425);
FORCEPROP 1 LAST BODY_TYPE PLUMBING
J 2
(-2775 2375);
DISPLAY 1.595745 (-2775 2375);
PAINT GREEN (-2775 2375);
DISPLAY INVISIBLE (-2775 2375);
FORCEPROP 1 LAST HDL_TAP TRUE
J 2
(-3100 2300);
DISPLAY 1.595745 (-3100 2300);
PAINT GREEN (-3100 2300);
DISPLAY INVISIBLE (-3100 2300);
FORCEPROP 1 LAST PATH I117
J 2
(-2773 2425);
DISPLAY 0.872340 (-2773 2425);
PAINT GREEN (-2773 2425);
DISPLAY INVISIBLE (-2773 2425);
FORCEADD TAP..6
R 2
(-2775 2475);
FORCEPROP 3 LASTPIN (-2825 2475) SIG_NAME M_D_MA<11>
J 0
(-2815 2485);
DISPLAY 0.659574 (-2815 2485);
PAINT MONO (-2815 2485);
DISPLAY INVISIBLE (-2815 2485);
FORCEPROP 1 LASTPIN (-2825 2475) BN 11
J 2
(-2773 2483);
DISPLAY 0.617021 (-2773 2483);
PAINT PINK (-2773 2483);
FORCEPROP 2 LAST CDS_LIB mstr_standard
J 0
(-2775 2475);
PAINT MONO (-2775 2475);
DISPLAY INVISIBLE (-2775 2475);
FORCEPROP 1 LAST BODY_TYPE PLUMBING
J 2
(-2775 2425);
DISPLAY 1.595745 (-2775 2425);
PAINT GREEN (-2775 2425);
DISPLAY INVISIBLE (-2775 2425);
FORCEPROP 1 LAST HDL_TAP TRUE
J 2
(-3100 2350);
DISPLAY 1.595745 (-3100 2350);
PAINT GREEN (-3100 2350);
DISPLAY INVISIBLE (-3100 2350);
FORCEPROP 1 LAST PATH I118
J 2
(-2773 2475);
DISPLAY 0.872340 (-2773 2475);
PAINT GREEN (-2773 2475);
DISPLAY INVISIBLE (-2773 2475);
FORCEADD TAP..6
R 2
(-2775 2575);
FORCEPROP 3 LASTPIN (-2825 2575) SIG_NAME M_D_MA<13>
J 0
(-2815 2585);
DISPLAY 0.659574 (-2815 2585);
PAINT MONO (-2815 2585);
DISPLAY INVISIBLE (-2815 2585);
FORCEPROP 1 LASTPIN (-2825 2575) BN 13
J 2
(-2773 2583);
DISPLAY 0.617021 (-2773 2583);
PAINT PINK (-2773 2583);
FORCEPROP 2 LAST CDS_LIB mstr_standard
J 0
(-2775 2575);
PAINT MONO (-2775 2575);
DISPLAY INVISIBLE (-2775 2575);
FORCEPROP 1 LAST BODY_TYPE PLUMBING
J 2
(-2775 2525);
DISPLAY 1.595745 (-2775 2525);
PAINT GREEN (-2775 2525);
DISPLAY INVISIBLE (-2775 2525);
FORCEPROP 1 LAST HDL_TAP TRUE
J 2
(-3100 2450);
DISPLAY 1.595745 (-3100 2450);
PAINT GREEN (-3100 2450);
DISPLAY INVISIBLE (-3100 2450);
FORCEPROP 1 LAST PATH I119
J 2
(-2773 2575);
DISPLAY 0.872340 (-2773 2575);
PAINT GREEN (-2773 2575);
DISPLAY INVISIBLE (-2773 2575);
FORCEADD TAP..6
(-5500 975);
FORCEPROP 3 LASTPIN (-5450 975) SIG_NAME M_D_CLK_DP<3>
J 0
(-5440 985);
DISPLAY 0.659574 (-5440 985);
PAINT MONO (-5440 985);
DISPLAY INVISIBLE (-5440 985);
FORCEPROP 1 LASTPIN (-5450 975) BN 3
J 0
(-5502 983);
DISPLAY 0.617021 (-5502 983);
PAINT PINK (-5502 983);
FORCEPROP 2 LAST CDS_LIB mstr_standard
J 0
(-5500 975);
PAINT MONO (-5500 975);
DISPLAY INVISIBLE (-5500 975);
FORCEPROP 1 LAST BODY_TYPE PLUMBING
J 0
(-5500 925);
DISPLAY 1.595745 (-5500 925);
PAINT GREEN (-5500 925);
DISPLAY INVISIBLE (-5500 925);
FORCEPROP 1 LAST HDL_TAP TRUE
J 0
(-5175 850);
DISPLAY 1.595745 (-5175 850);
PAINT GREEN (-5175 850);
DISPLAY INVISIBLE (-5175 850);
FORCEPROP 1 LAST PATH I12
J 0
(-5502 975);
DISPLAY 0.872340 (-5502 975);
PAINT GREEN (-5502 975);
DISPLAY INVISIBLE (-5502 975);
FORCEADD TAP..6
R 2
(-2775 2525);
FORCEPROP 3 LASTPIN (-2825 2525) SIG_NAME M_D_MA<12>
J 0
(-2815 2535);
DISPLAY 0.659574 (-2815 2535);
PAINT MONO (-2815 2535);
DISPLAY INVISIBLE (-2815 2535);
FORCEPROP 1 LASTPIN (-2825 2525) BN 12
J 2
(-2773 2533);
DISPLAY 0.617021 (-2773 2533);
PAINT PINK (-2773 2533);
FORCEPROP 2 LAST CDS_LIB mstr_standard
J 0
(-2775 2525);
PAINT MONO (-2775 2525);
DISPLAY INVISIBLE (-2775 2525);
FORCEPROP 1 LAST BODY_TYPE PLUMBING
J 2
(-2775 2475);
DISPLAY 1.595745 (-2775 2475);
PAINT GREEN (-2775 2475);
DISPLAY INVISIBLE (-2775 2475);
FORCEPROP 1 LAST HDL_TAP TRUE
J 2
(-3100 2400);
DISPLAY 1.595745 (-3100 2400);
PAINT GREEN (-3100 2400);
DISPLAY INVISIBLE (-3100 2400);
FORCEPROP 1 LAST PATH I120
J 2
(-2773 2525);
DISPLAY 0.872340 (-2773 2525);
PAINT GREEN (-2773 2525);
DISPLAY INVISIBLE (-2773 2525);
FORCEADD TAP..6
R 2
(-2775 2675);
FORCEPROP 3 LASTPIN (-2825 2675) SIG_NAME M_D_MA<15>
J 0
(-2815 2685);
DISPLAY 0.659574 (-2815 2685);
PAINT MONO (-2815 2685);
DISPLAY INVISIBLE (-2815 2685);
FORCEPROP 1 LASTPIN (-2825 2675) BN 15
J 2
(-2773 2683);
DISPLAY 0.617021 (-2773 2683);
PAINT PINK (-2773 2683);
FORCEPROP 2 LAST CDS_LIB mstr_standard
J 0
(-2775 2675);
PAINT MONO (-2775 2675);
DISPLAY INVISIBLE (-2775 2675);
FORCEPROP 1 LAST BODY_TYPE PLUMBING
J 2
(-2775 2625);
DISPLAY 1.595745 (-2775 2625);
PAINT GREEN (-2775 2625);
DISPLAY INVISIBLE (-2775 2625);
FORCEPROP 1 LAST HDL_TAP TRUE
J 2
(-3100 2550);
DISPLAY 1.595745 (-3100 2550);
PAINT GREEN (-3100 2550);
DISPLAY INVISIBLE (-3100 2550);
FORCEPROP 1 LAST PATH I121
J 2
(-2773 2675);
DISPLAY 0.872340 (-2773 2675);
PAINT GREEN (-2773 2675);
DISPLAY INVISIBLE (-2773 2675);
FORCEADD TAP..6
R 2
(-2775 2725);
FORCEPROP 3 LASTPIN (-2825 2725) SIG_NAME M_D_MA<16>
J 0
(-2815 2735);
DISPLAY 0.659574 (-2815 2735);
PAINT MONO (-2815 2735);
DISPLAY INVISIBLE (-2815 2735);
FORCEPROP 1 LASTPIN (-2825 2725) BN 16
J 2
(-2773 2733);
DISPLAY 0.617021 (-2773 2733);
PAINT PINK (-2773 2733);
FORCEPROP 2 LAST CDS_LIB mstr_standard
J 0
(-2775 2725);
PAINT MONO (-2775 2725);
DISPLAY INVISIBLE (-2775 2725);
FORCEPROP 1 LAST BODY_TYPE PLUMBING
J 2
(-2775 2675);
DISPLAY 1.595745 (-2775 2675);
PAINT GREEN (-2775 2675);
DISPLAY INVISIBLE (-2775 2675);
FORCEPROP 1 LAST HDL_TAP TRUE
J 2
(-3100 2600);
DISPLAY 1.595745 (-3100 2600);
PAINT GREEN (-3100 2600);
DISPLAY INVISIBLE (-3100 2600);
FORCEPROP 1 LAST PATH I122
J 2
(-2773 2725);
DISPLAY 0.872340 (-2773 2725);
PAINT GREEN (-2773 2725);
DISPLAY INVISIBLE (-2773 2725);
FORCEADD TAP..6
R 2
(-2775 2625);
FORCEPROP 3 LASTPIN (-2825 2625) SIG_NAME M_D_MA<14>
J 0
(-2815 2635);
DISPLAY 0.659574 (-2815 2635);
PAINT MONO (-2815 2635);
DISPLAY INVISIBLE (-2815 2635);
FORCEPROP 1 LASTPIN (-2825 2625) BN 14
J 2
(-2773 2633);
DISPLAY 0.617021 (-2773 2633);
PAINT PINK (-2773 2633);
FORCEPROP 2 LAST CDS_LIB mstr_standard
J 0
(-2775 2625);
PAINT MONO (-2775 2625);
DISPLAY INVISIBLE (-2775 2625);
FORCEPROP 1 LAST BODY_TYPE PLUMBING
J 2
(-2775 2575);
DISPLAY 1.595745 (-2775 2575);
PAINT GREEN (-2775 2575);
DISPLAY INVISIBLE (-2775 2575);
FORCEPROP 1 LAST HDL_TAP TRUE
J 2
(-3100 2500);
DISPLAY 1.595745 (-3100 2500);
PAINT GREEN (-3100 2500);
DISPLAY INVISIBLE (-3100 2500);
FORCEPROP 1 LAST PATH I123
J 2
(-2773 2625);
DISPLAY 0.872340 (-2773 2625);
PAINT GREEN (-2773 2625);
DISPLAY INVISIBLE (-2773 2625);
FORCEADD TAP..6
R 2
(-2775 2775);
FORCEPROP 3 LASTPIN (-2825 2775) SIG_NAME M_D_MA<17>
J 0
(-2815 2785);
DISPLAY 0.659574 (-2815 2785);
PAINT MONO (-2815 2785);
DISPLAY INVISIBLE (-2815 2785);
FORCEPROP 1 LASTPIN (-2825 2775) BN 17
J 2
(-2773 2783);
DISPLAY 0.617021 (-2773 2783);
PAINT PINK (-2773 2783);
FORCEPROP 2 LAST CDS_LIB mstr_standard
J 0
(-2775 2775);
PAINT MONO (-2775 2775);
DISPLAY INVISIBLE (-2775 2775);
FORCEPROP 1 LAST BODY_TYPE PLUMBING
J 2
(-2775 2725);
DISPLAY 1.595745 (-2775 2725);
PAINT GREEN (-2775 2725);
DISPLAY INVISIBLE (-2775 2725);
FORCEPROP 1 LAST HDL_TAP TRUE
J 2
(-3100 2650);
DISPLAY 1.595745 (-3100 2650);
PAINT GREEN (-3100 2650);
DISPLAY INVISIBLE (-3100 2650);
FORCEPROP 1 LAST PATH I124
J 2
(-2773 2775);
DISPLAY 0.872340 (-2773 2775);
PAINT GREEN (-2773 2775);
DISPLAY INVISIBLE (-2773 2775);
FORCEADD TAP..6
R 2
(-2775 2925);
FORCEPROP 3 LASTPIN (-2825 2925) SIG_NAME M_D_DQS_DN<1>
J 0
(-2815 2935);
DISPLAY 0.659574 (-2815 2935);
PAINT MONO (-2815 2935);
DISPLAY INVISIBLE (-2815 2935);
FORCEPROP 1 LASTPIN (-2825 2925) BN 1
J 2
(-2773 2933);
DISPLAY 0.617021 (-2773 2933);
PAINT PINK (-2773 2933);
FORCEPROP 2 LAST CDS_LIB mstr_standard
J 0
(-2775 2925);
PAINT MONO (-2775 2925);
DISPLAY INVISIBLE (-2775 2925);
FORCEPROP 1 LAST BODY_TYPE PLUMBING
J 2
(-2775 2875);
DISPLAY 1.595745 (-2775 2875);
PAINT GREEN (-2775 2875);
DISPLAY INVISIBLE (-2775 2875);
FORCEPROP 1 LAST HDL_TAP TRUE
J 2
(-3100 2800);
DISPLAY 1.595745 (-3100 2800);
PAINT GREEN (-3100 2800);
DISPLAY INVISIBLE (-3100 2800);
FORCEPROP 1 LAST PATH I125
J 2
(-2773 2925);
DISPLAY 0.872340 (-2773 2925);
PAINT GREEN (-2773 2925);
DISPLAY INVISIBLE (-2773 2925);
FORCEADD TAP..6
R 2
(-2775 2975);
FORCEPROP 3 LASTPIN (-2825 2975) SIG_NAME M_D_DQS_DN<2>
J 0
(-2815 2985);
DISPLAY 0.659574 (-2815 2985);
PAINT MONO (-2815 2985);
DISPLAY INVISIBLE (-2815 2985);
FORCEPROP 1 LASTPIN (-2825 2975) BN 2
J 2
(-2773 2983);
DISPLAY 0.617021 (-2773 2983);
PAINT PINK (-2773 2983);
FORCEPROP 2 LAST CDS_LIB mstr_standard
J 0
(-2775 2975);
PAINT MONO (-2775 2975);
DISPLAY INVISIBLE (-2775 2975);
FORCEPROP 1 LAST BODY_TYPE PLUMBING
J 2
(-2775 2925);
DISPLAY 1.595745 (-2775 2925);
PAINT GREEN (-2775 2925);
DISPLAY INVISIBLE (-2775 2925);
FORCEPROP 1 LAST HDL_TAP TRUE
J 2
(-3100 2850);
DISPLAY 1.595745 (-3100 2850);
PAINT GREEN (-3100 2850);
DISPLAY INVISIBLE (-3100 2850);
FORCEPROP 1 LAST PATH I126
J 2
(-2773 2975);
DISPLAY 0.872340 (-2773 2975);
PAINT GREEN (-2773 2975);
DISPLAY INVISIBLE (-2773 2975);
FORCEADD TAP..6
R 2
(-2775 2875);
FORCEPROP 3 LASTPIN (-2825 2875) SIG_NAME M_D_DQS_DN<0>
J 0
(-2815 2885);
DISPLAY 0.659574 (-2815 2885);
PAINT MONO (-2815 2885);
DISPLAY INVISIBLE (-2815 2885);
FORCEPROP 1 LASTPIN (-2825 2875) BN 0
J 2
(-2773 2883);
DISPLAY 0.617021 (-2773 2883);
PAINT PINK (-2773 2883);
FORCEPROP 2 LAST CDS_LIB mstr_standard
J 0
(-2775 2875);
PAINT MONO (-2775 2875);
DISPLAY INVISIBLE (-2775 2875);
FORCEPROP 1 LAST BODY_TYPE PLUMBING
J 2
(-2775 2825);
DISPLAY 1.595745 (-2775 2825);
PAINT GREEN (-2775 2825);
DISPLAY INVISIBLE (-2775 2825);
FORCEPROP 1 LAST HDL_TAP TRUE
J 2
(-3100 2750);
DISPLAY 1.595745 (-3100 2750);
PAINT GREEN (-3100 2750);
DISPLAY INVISIBLE (-3100 2750);
FORCEPROP 1 LAST PATH I127
J 2
(-2773 2875);
DISPLAY 0.872340 (-2773 2875);
PAINT GREEN (-2773 2875);
DISPLAY INVISIBLE (-2773 2875);
FORCEADD TAP..6
R 2
(-2775 3025);
FORCEPROP 3 LASTPIN (-2825 3025) SIG_NAME M_D_DQS_DN<3>
J 0
(-2815 3035);
DISPLAY 0.659574 (-2815 3035);
PAINT MONO (-2815 3035);
DISPLAY INVISIBLE (-2815 3035);
FORCEPROP 1 LASTPIN (-2825 3025) BN 3
J 2
(-2773 3033);
DISPLAY 0.617021 (-2773 3033);
PAINT PINK (-2773 3033);
FORCEPROP 2 LAST CDS_LIB mstr_standard
J 0
(-2775 3025);
PAINT MONO (-2775 3025);
DISPLAY INVISIBLE (-2775 3025);
FORCEPROP 1 LAST BODY_TYPE PLUMBING
J 2
(-2775 2975);
DISPLAY 1.595745 (-2775 2975);
PAINT GREEN (-2775 2975);
DISPLAY INVISIBLE (-2775 2975);
FORCEPROP 1 LAST HDL_TAP TRUE
J 2
(-3100 2900);
DISPLAY 1.595745 (-3100 2900);
PAINT GREEN (-3100 2900);
DISPLAY INVISIBLE (-3100 2900);
FORCEPROP 1 LAST PATH I128
J 2
(-2773 3025);
DISPLAY 0.872340 (-2773 3025);
PAINT GREEN (-2773 3025);
DISPLAY INVISIBLE (-2773 3025);
FORCEADD TAP..6
R 2
(-2775 3075);
FORCEPROP 3 LASTPIN (-2825 3075) SIG_NAME M_D_DQS_DN<4>
J 0
(-2815 3085);
DISPLAY 0.659574 (-2815 3085);
PAINT MONO (-2815 3085);
DISPLAY INVISIBLE (-2815 3085);
FORCEPROP 1 LASTPIN (-2825 3075) BN 4
J 2
(-2773 3083);
DISPLAY 0.617021 (-2773 3083);
PAINT PINK (-2773 3083);
FORCEPROP 2 LAST CDS_LIB mstr_standard
J 0
(-2775 3075);
PAINT MONO (-2775 3075);
DISPLAY INVISIBLE (-2775 3075);
FORCEPROP 1 LAST BODY_TYPE PLUMBING
J 2
(-2775 3025);
DISPLAY 1.595745 (-2775 3025);
PAINT GREEN (-2775 3025);
DISPLAY INVISIBLE (-2775 3025);
FORCEPROP 1 LAST HDL_TAP TRUE
J 2
(-3100 2950);
DISPLAY 1.595745 (-3100 2950);
PAINT GREEN (-3100 2950);
DISPLAY INVISIBLE (-3100 2950);
FORCEPROP 1 LAST PATH I129
J 2
(-2773 3075);
DISPLAY 0.872340 (-2773 3075);
PAINT GREEN (-2773 3075);
DISPLAY INVISIBLE (-2773 3075);
FORCEADD TAP..6
(-5500 1075);
FORCEPROP 3 LASTPIN (-5450 1075) SIG_NAME M_D_ECC<0>
J 0
(-5440 1085);
DISPLAY 0.659574 (-5440 1085);
PAINT MONO (-5440 1085);
DISPLAY INVISIBLE (-5440 1085);
FORCEPROP 1 LASTPIN (-5450 1075) BN 0
J 0
(-5502 1083);
DISPLAY 0.617021 (-5502 1083);
PAINT PINK (-5502 1083);
FORCEPROP 2 LAST CDS_LIB mstr_standard
J 0
(-5500 1075);
PAINT MONO (-5500 1075);
DISPLAY INVISIBLE (-5500 1075);
FORCEPROP 1 LAST BODY_TYPE PLUMBING
J 0
(-5500 1025);
DISPLAY 1.595745 (-5500 1025);
PAINT GREEN (-5500 1025);
DISPLAY INVISIBLE (-5500 1025);
FORCEPROP 1 LAST HDL_TAP TRUE
J 0
(-5175 950);
DISPLAY 1.595745 (-5175 950);
PAINT GREEN (-5175 950);
DISPLAY INVISIBLE (-5175 950);
FORCEPROP 1 LAST PATH I13
J 0
(-5502 1075);
DISPLAY 0.872340 (-5502 1075);
PAINT GREEN (-5502 1075);
DISPLAY INVISIBLE (-5502 1075);
FORCEADD TAP..6
R 2
(-2775 3125);
FORCEPROP 3 LASTPIN (-2825 3125) SIG_NAME M_D_DQS_DN<5>
J 0
(-2815 3135);
DISPLAY 0.659574 (-2815 3135);
PAINT MONO (-2815 3135);
DISPLAY INVISIBLE (-2815 3135);
FORCEPROP 1 LASTPIN (-2825 3125) BN 5
J 2
(-2773 3133);
DISPLAY 0.617021 (-2773 3133);
PAINT PINK (-2773 3133);
FORCEPROP 2 LAST CDS_LIB mstr_standard
J 0
(-2775 3125);
PAINT MONO (-2775 3125);
DISPLAY INVISIBLE (-2775 3125);
FORCEPROP 1 LAST BODY_TYPE PLUMBING
J 2
(-2775 3075);
DISPLAY 1.595745 (-2775 3075);
PAINT GREEN (-2775 3075);
DISPLAY INVISIBLE (-2775 3075);
FORCEPROP 1 LAST HDL_TAP TRUE
J 2
(-3100 3000);
DISPLAY 1.595745 (-3100 3000);
PAINT GREEN (-3100 3000);
DISPLAY INVISIBLE (-3100 3000);
FORCEPROP 1 LAST PATH I130
J 2
(-2773 3125);
DISPLAY 0.872340 (-2773 3125);
PAINT GREEN (-2773 3125);
DISPLAY INVISIBLE (-2773 3125);
FORCEADD TAP..6
R 2
(-2775 3175);
FORCEPROP 3 LASTPIN (-2825 3175) SIG_NAME M_D_DQS_DN<6>
J 0
(-2815 3185);
DISPLAY 0.659574 (-2815 3185);
PAINT MONO (-2815 3185);
DISPLAY INVISIBLE (-2815 3185);
FORCEPROP 1 LASTPIN (-2825 3175) BN 6
J 2
(-2773 3183);
DISPLAY 0.617021 (-2773 3183);
PAINT PINK (-2773 3183);
FORCEPROP 2 LAST CDS_LIB mstr_standard
J 0
(-2775 3175);
PAINT MONO (-2775 3175);
DISPLAY INVISIBLE (-2775 3175);
FORCEPROP 1 LAST BODY_TYPE PLUMBING
J 2
(-2775 3125);
DISPLAY 1.595745 (-2775 3125);
PAINT GREEN (-2775 3125);
DISPLAY INVISIBLE (-2775 3125);
FORCEPROP 1 LAST HDL_TAP TRUE
J 2
(-3100 3050);
DISPLAY 1.595745 (-3100 3050);
PAINT GREEN (-3100 3050);
DISPLAY INVISIBLE (-3100 3050);
FORCEPROP 1 LAST PATH I131
J 2
(-2773 3175);
DISPLAY 0.872340 (-2773 3175);
PAINT GREEN (-2773 3175);
DISPLAY INVISIBLE (-2773 3175);
FORCEADD TAP..6
R 2
(-2775 3225);
FORCEPROP 3 LASTPIN (-2825 3225) SIG_NAME M_D_DQS_DN<7>
J 0
(-2815 3235);
DISPLAY 0.659574 (-2815 3235);
PAINT MONO (-2815 3235);
DISPLAY INVISIBLE (-2815 3235);
FORCEPROP 1 LASTPIN (-2825 3225) BN 7
J 2
(-2773 3233);
DISPLAY 0.617021 (-2773 3233);
PAINT PINK (-2773 3233);
FORCEPROP 2 LAST CDS_LIB mstr_standard
J 0
(-2775 3225);
PAINT MONO (-2775 3225);
DISPLAY INVISIBLE (-2775 3225);
FORCEPROP 1 LAST BODY_TYPE PLUMBING
J 2
(-2775 3175);
DISPLAY 1.595745 (-2775 3175);
PAINT GREEN (-2775 3175);
DISPLAY INVISIBLE (-2775 3175);
FORCEPROP 1 LAST HDL_TAP TRUE
J 2
(-3100 3100);
DISPLAY 1.595745 (-3100 3100);
PAINT GREEN (-3100 3100);
DISPLAY INVISIBLE (-3100 3100);
FORCEPROP 1 LAST PATH I132
J 2
(-2773 3225);
DISPLAY 0.872340 (-2773 3225);
PAINT GREEN (-2773 3225);
DISPLAY INVISIBLE (-2773 3225);
FORCEADD TAP..6
R 2
(-2775 3275);
FORCEPROP 3 LASTPIN (-2825 3275) SIG_NAME M_D_DQS_DN<8>
J 0
(-2815 3285);
DISPLAY 0.659574 (-2815 3285);
PAINT MONO (-2815 3285);
DISPLAY INVISIBLE (-2815 3285);
FORCEPROP 1 LASTPIN (-2825 3275) BN 8
J 2
(-2773 3283);
DISPLAY 0.617021 (-2773 3283);
PAINT PINK (-2773 3283);
FORCEPROP 2 LAST CDS_LIB mstr_standard
J 0
(-2775 3275);
PAINT MONO (-2775 3275);
DISPLAY INVISIBLE (-2775 3275);
FORCEPROP 1 LAST BODY_TYPE PLUMBING
J 2
(-2775 3225);
DISPLAY 1.595745 (-2775 3225);
PAINT GREEN (-2775 3225);
DISPLAY INVISIBLE (-2775 3225);
FORCEPROP 1 LAST HDL_TAP TRUE
J 2
(-3100 3150);
DISPLAY 1.595745 (-3100 3150);
PAINT GREEN (-3100 3150);
DISPLAY INVISIBLE (-3100 3150);
FORCEPROP 1 LAST PATH I133
J 2
(-2773 3275);
DISPLAY 0.872340 (-2773 3275);
PAINT GREEN (-2773 3275);
DISPLAY INVISIBLE (-2773 3275);
FORCEADD TAP..6
R 2
(-2775 3325);
FORCEPROP 3 LASTPIN (-2825 3325) SIG_NAME M_D_DQS_DN<9>
J 0
(-2815 3335);
DISPLAY 0.659574 (-2815 3335);
PAINT MONO (-2815 3335);
DISPLAY INVISIBLE (-2815 3335);
FORCEPROP 1 LASTPIN (-2825 3325) BN 9
J 2
(-2773 3333);
DISPLAY 0.617021 (-2773 3333);
PAINT PINK (-2773 3333);
FORCEPROP 2 LAST CDS_LIB mstr_standard
J 0
(-2775 3325);
PAINT MONO (-2775 3325);
DISPLAY INVISIBLE (-2775 3325);
FORCEPROP 1 LAST BODY_TYPE PLUMBING
J 2
(-2775 3275);
DISPLAY 1.595745 (-2775 3275);
PAINT GREEN (-2775 3275);
DISPLAY INVISIBLE (-2775 3275);
FORCEPROP 1 LAST HDL_TAP TRUE
J 2
(-3100 3200);
DISPLAY 1.595745 (-3100 3200);
PAINT GREEN (-3100 3200);
DISPLAY INVISIBLE (-3100 3200);
FORCEPROP 1 LAST PATH I134
J 2
(-2773 3325);
DISPLAY 0.872340 (-2773 3325);
PAINT GREEN (-2773 3325);
DISPLAY INVISIBLE (-2773 3325);
FORCEADD TAP..6
R 2
(-2775 3375);
FORCEPROP 3 LASTPIN (-2825 3375) SIG_NAME M_D_DQS_DN<10>
J 0
(-2815 3385);
DISPLAY 0.659574 (-2815 3385);
PAINT MONO (-2815 3385);
DISPLAY INVISIBLE (-2815 3385);
FORCEPROP 1 LASTPIN (-2825 3375) BN 10
J 2
(-2773 3383);
DISPLAY 0.617021 (-2773 3383);
PAINT PINK (-2773 3383);
FORCEPROP 2 LAST CDS_LIB mstr_standard
J 0
(-2775 3375);
PAINT MONO (-2775 3375);
DISPLAY INVISIBLE (-2775 3375);
FORCEPROP 1 LAST BODY_TYPE PLUMBING
J 2
(-2775 3325);
DISPLAY 1.595745 (-2775 3325);
PAINT GREEN (-2775 3325);
DISPLAY INVISIBLE (-2775 3325);
FORCEPROP 1 LAST HDL_TAP TRUE
J 2
(-3100 3250);
DISPLAY 1.595745 (-3100 3250);
PAINT GREEN (-3100 3250);
DISPLAY INVISIBLE (-3100 3250);
FORCEPROP 1 LAST PATH I135
J 2
(-2773 3375);
DISPLAY 0.872340 (-2773 3375);
PAINT GREEN (-2773 3375);
DISPLAY INVISIBLE (-2773 3375);
FORCEADD TAP..6
R 2
(-2775 3475);
FORCEPROP 3 LASTPIN (-2825 3475) SIG_NAME M_D_DQS_DN<12>
J 0
(-2815 3485);
DISPLAY 0.659574 (-2815 3485);
PAINT MONO (-2815 3485);
DISPLAY INVISIBLE (-2815 3485);
FORCEPROP 1 LASTPIN (-2825 3475) BN 12
J 2
(-2773 3483);
DISPLAY 0.617021 (-2773 3483);
PAINT PINK (-2773 3483);
FORCEPROP 2 LAST CDS_LIB mstr_standard
J 0
(-2775 3475);
PAINT MONO (-2775 3475);
DISPLAY INVISIBLE (-2775 3475);
FORCEPROP 1 LAST BODY_TYPE PLUMBING
J 2
(-2775 3425);
DISPLAY 1.595745 (-2775 3425);
PAINT GREEN (-2775 3425);
DISPLAY INVISIBLE (-2775 3425);
FORCEPROP 1 LAST HDL_TAP TRUE
J 2
(-3100 3350);
DISPLAY 1.595745 (-3100 3350);
PAINT GREEN (-3100 3350);
DISPLAY INVISIBLE (-3100 3350);
FORCEPROP 1 LAST PATH I136
J 2
(-2773 3475);
DISPLAY 0.872340 (-2773 3475);
PAINT GREEN (-2773 3475);
DISPLAY INVISIBLE (-2773 3475);
FORCEADD TAP..6
R 2
(-2775 3425);
FORCEPROP 3 LASTPIN (-2825 3425) SIG_NAME M_D_DQS_DN<11>
J 0
(-2815 3435);
DISPLAY 0.659574 (-2815 3435);
PAINT MONO (-2815 3435);
DISPLAY INVISIBLE (-2815 3435);
FORCEPROP 1 LASTPIN (-2825 3425) BN 11
J 2
(-2773 3433);
DISPLAY 0.617021 (-2773 3433);
PAINT PINK (-2773 3433);
FORCEPROP 2 LAST CDS_LIB mstr_standard
J 0
(-2775 3425);
PAINT MONO (-2775 3425);
DISPLAY INVISIBLE (-2775 3425);
FORCEPROP 1 LAST BODY_TYPE PLUMBING
J 2
(-2775 3375);
DISPLAY 1.595745 (-2775 3375);
PAINT GREEN (-2775 3375);
DISPLAY INVISIBLE (-2775 3375);
FORCEPROP 1 LAST HDL_TAP TRUE
J 2
(-3100 3300);
DISPLAY 1.595745 (-3100 3300);
PAINT GREEN (-3100 3300);
DISPLAY INVISIBLE (-3100 3300);
FORCEPROP 1 LAST PATH I137
J 2
(-2773 3425);
DISPLAY 0.872340 (-2773 3425);
PAINT GREEN (-2773 3425);
DISPLAY INVISIBLE (-2773 3425);
FORCEADD TAP..6
R 2
(-2775 3575);
FORCEPROP 3 LASTPIN (-2825 3575) SIG_NAME M_D_DQS_DN<14>
J 0
(-2815 3585);
DISPLAY 0.659574 (-2815 3585);
PAINT MONO (-2815 3585);
DISPLAY INVISIBLE (-2815 3585);
FORCEPROP 1 LASTPIN (-2825 3575) BN 14
J 2
(-2773 3583);
DISPLAY 0.617021 (-2773 3583);
PAINT PINK (-2773 3583);
FORCEPROP 2 LAST CDS_LIB mstr_standard
J 0
(-2775 3575);
PAINT MONO (-2775 3575);
DISPLAY INVISIBLE (-2775 3575);
FORCEPROP 1 LAST BODY_TYPE PLUMBING
J 2
(-2775 3525);
DISPLAY 1.595745 (-2775 3525);
PAINT GREEN (-2775 3525);
DISPLAY INVISIBLE (-2775 3525);
FORCEPROP 1 LAST HDL_TAP TRUE
J 2
(-3100 3450);
DISPLAY 1.595745 (-3100 3450);
PAINT GREEN (-3100 3450);
DISPLAY INVISIBLE (-3100 3450);
FORCEPROP 1 LAST PATH I138
J 2
(-2773 3575);
DISPLAY 0.872340 (-2773 3575);
PAINT GREEN (-2773 3575);
DISPLAY INVISIBLE (-2773 3575);
FORCEADD TAP..6
R 2
(-2775 3625);
FORCEPROP 3 LASTPIN (-2825 3625) SIG_NAME M_D_DQS_DN<15>
J 0
(-2815 3635);
DISPLAY 0.659574 (-2815 3635);
PAINT MONO (-2815 3635);
DISPLAY INVISIBLE (-2815 3635);
FORCEPROP 1 LASTPIN (-2825 3625) BN 15
J 2
(-2773 3633);
DISPLAY 0.617021 (-2773 3633);
PAINT PINK (-2773 3633);
FORCEPROP 2 LAST CDS_LIB mstr_standard
J 0
(-2775 3625);
PAINT MONO (-2775 3625);
DISPLAY INVISIBLE (-2775 3625);
FORCEPROP 1 LAST BODY_TYPE PLUMBING
J 2
(-2775 3575);
DISPLAY 1.595745 (-2775 3575);
PAINT GREEN (-2775 3575);
DISPLAY INVISIBLE (-2775 3575);
FORCEPROP 1 LAST HDL_TAP TRUE
J 2
(-3100 3500);
DISPLAY 1.595745 (-3100 3500);
PAINT GREEN (-3100 3500);
DISPLAY INVISIBLE (-3100 3500);
FORCEPROP 1 LAST PATH I139
J 2
(-2773 3625);
DISPLAY 0.872340 (-2773 3625);
PAINT GREEN (-2773 3625);
DISPLAY INVISIBLE (-2773 3625);
FORCEADD TAP..6
(-5500 1125);
FORCEPROP 3 LASTPIN (-5450 1125) SIG_NAME M_D_ECC<1>
J 0
(-5440 1135);
DISPLAY 0.659574 (-5440 1135);
PAINT MONO (-5440 1135);
DISPLAY INVISIBLE (-5440 1135);
FORCEPROP 1 LASTPIN (-5450 1125) BN 1
J 0
(-5502 1133);
DISPLAY 0.617021 (-5502 1133);
PAINT PINK (-5502 1133);
FORCEPROP 2 LAST CDS_LIB mstr_standard
J 0
(-5500 1125);
PAINT MONO (-5500 1125);
DISPLAY INVISIBLE (-5500 1125);
FORCEPROP 1 LAST BODY_TYPE PLUMBING
J 0
(-5500 1075);
DISPLAY 1.595745 (-5500 1075);
PAINT GREEN (-5500 1075);
DISPLAY INVISIBLE (-5500 1075);
FORCEPROP 1 LAST HDL_TAP TRUE
J 0
(-5175 1000);
DISPLAY 1.595745 (-5175 1000);
PAINT GREEN (-5175 1000);
DISPLAY INVISIBLE (-5175 1000);
FORCEPROP 1 LAST PATH I14
J 0
(-5502 1125);
DISPLAY 0.872340 (-5502 1125);
PAINT GREEN (-5502 1125);
DISPLAY INVISIBLE (-5502 1125);
FORCEADD TAP..6
R 2
(-2775 3525);
FORCEPROP 3 LASTPIN (-2825 3525) SIG_NAME M_D_DQS_DN<13>
J 0
(-2815 3535);
DISPLAY 0.659574 (-2815 3535);
PAINT MONO (-2815 3535);
DISPLAY INVISIBLE (-2815 3535);
FORCEPROP 1 LASTPIN (-2825 3525) BN 13
J 2
(-2773 3533);
DISPLAY 0.617021 (-2773 3533);
PAINT PINK (-2773 3533);
FORCEPROP 2 LAST CDS_LIB mstr_standard
J 0
(-2775 3525);
PAINT MONO (-2775 3525);
DISPLAY INVISIBLE (-2775 3525);
FORCEPROP 1 LAST BODY_TYPE PLUMBING
J 2
(-2775 3475);
DISPLAY 1.595745 (-2775 3475);
PAINT GREEN (-2775 3475);
DISPLAY INVISIBLE (-2775 3475);
FORCEPROP 1 LAST HDL_TAP TRUE
J 2
(-3100 3400);
DISPLAY 1.595745 (-3100 3400);
PAINT GREEN (-3100 3400);
DISPLAY INVISIBLE (-3100 3400);
FORCEPROP 1 LAST PATH I140
J 2
(-2773 3525);
DISPLAY 0.872340 (-2773 3525);
PAINT GREEN (-2773 3525);
DISPLAY INVISIBLE (-2773 3525);
FORCEADD TAP..6
R 2
(-2775 3725);
FORCEPROP 3 LASTPIN (-2825 3725) SIG_NAME M_D_DQS_DN<17>
J 0
(-2815 3735);
DISPLAY 0.659574 (-2815 3735);
PAINT MONO (-2815 3735);
DISPLAY INVISIBLE (-2815 3735);
FORCEPROP 1 LASTPIN (-2825 3725) BN 17
J 2
(-2773 3733);
DISPLAY 0.617021 (-2773 3733);
PAINT PINK (-2773 3733);
FORCEPROP 2 LAST CDS_LIB mstr_standard
J 0
(-2775 3725);
PAINT MONO (-2775 3725);
DISPLAY INVISIBLE (-2775 3725);
FORCEPROP 1 LAST BODY_TYPE PLUMBING
J 2
(-2775 3675);
DISPLAY 1.595745 (-2775 3675);
PAINT GREEN (-2775 3675);
DISPLAY INVISIBLE (-2775 3675);
FORCEPROP 1 LAST HDL_TAP TRUE
J 2
(-3100 3600);
DISPLAY 1.595745 (-3100 3600);
PAINT GREEN (-3100 3600);
DISPLAY INVISIBLE (-3100 3600);
FORCEPROP 1 LAST PATH I141
J 2
(-2773 3725);
DISPLAY 0.872340 (-2773 3725);
PAINT GREEN (-2773 3725);
DISPLAY INVISIBLE (-2773 3725);
FORCEADD TAP..6
R 2
(-2775 3675);
FORCEPROP 3 LASTPIN (-2825 3675) SIG_NAME M_D_DQS_DN<16>
J 0
(-2815 3685);
DISPLAY 0.659574 (-2815 3685);
PAINT MONO (-2815 3685);
DISPLAY INVISIBLE (-2815 3685);
FORCEPROP 1 LASTPIN (-2825 3675) BN 16
J 2
(-2773 3683);
DISPLAY 0.617021 (-2773 3683);
PAINT PINK (-2773 3683);
FORCEPROP 2 LAST CDS_LIB mstr_standard
J 0
(-2775 3675);
PAINT MONO (-2775 3675);
DISPLAY INVISIBLE (-2775 3675);
FORCEPROP 1 LAST BODY_TYPE PLUMBING
J 2
(-2775 3625);
DISPLAY 1.595745 (-2775 3625);
PAINT GREEN (-2775 3625);
DISPLAY INVISIBLE (-2775 3625);
FORCEPROP 1 LAST HDL_TAP TRUE
J 2
(-3100 3550);
DISPLAY 1.595745 (-3100 3550);
PAINT GREEN (-3100 3550);
DISPLAY INVISIBLE (-3100 3550);
FORCEPROP 1 LAST PATH I142
J 2
(-2773 3675);
DISPLAY 0.872340 (-2773 3675);
PAINT GREEN (-2773 3675);
DISPLAY INVISIBLE (-2773 3675);
FORCEADD TAP..6
R 2
(-2775 3875);
FORCEPROP 3 LASTPIN (-2825 3875) SIG_NAME M_D_DQS_DP<1>
J 0
(-2815 3885);
DISPLAY 0.659574 (-2815 3885);
PAINT MONO (-2815 3885);
DISPLAY INVISIBLE (-2815 3885);
FORCEPROP 1 LASTPIN (-2825 3875) BN 1
J 2
(-2773 3883);
DISPLAY 0.617021 (-2773 3883);
PAINT PINK (-2773 3883);
FORCEPROP 2 LAST CDS_LIB mstr_standard
J 0
(-2775 3875);
PAINT MONO (-2775 3875);
DISPLAY INVISIBLE (-2775 3875);
FORCEPROP 1 LAST BODY_TYPE PLUMBING
J 2
(-2775 3825);
DISPLAY 1.595745 (-2775 3825);
PAINT GREEN (-2775 3825);
DISPLAY INVISIBLE (-2775 3825);
FORCEPROP 1 LAST HDL_TAP TRUE
J 2
(-3100 3750);
DISPLAY 1.595745 (-3100 3750);
PAINT GREEN (-3100 3750);
DISPLAY INVISIBLE (-3100 3750);
FORCEPROP 1 LAST PATH I143
J 2
(-2773 3875);
DISPLAY 0.872340 (-2773 3875);
PAINT GREEN (-2773 3875);
DISPLAY INVISIBLE (-2773 3875);
FORCEADD TAP..6
R 2
(-2775 3825);
FORCEPROP 3 LASTPIN (-2825 3825) SIG_NAME M_D_DQS_DP<0>
J 0
(-2815 3835);
DISPLAY 0.659574 (-2815 3835);
PAINT MONO (-2815 3835);
DISPLAY INVISIBLE (-2815 3835);
FORCEPROP 1 LASTPIN (-2825 3825) BN 0
J 2
(-2773 3833);
DISPLAY 0.617021 (-2773 3833);
PAINT PINK (-2773 3833);
FORCEPROP 2 LAST CDS_LIB mstr_standard
J 0
(-2775 3825);
PAINT MONO (-2775 3825);
DISPLAY INVISIBLE (-2775 3825);
FORCEPROP 1 LAST BODY_TYPE PLUMBING
J 2
(-2775 3775);
DISPLAY 1.595745 (-2775 3775);
PAINT GREEN (-2775 3775);
DISPLAY INVISIBLE (-2775 3775);
FORCEPROP 1 LAST HDL_TAP TRUE
J 2
(-3100 3700);
DISPLAY 1.595745 (-3100 3700);
PAINT GREEN (-3100 3700);
DISPLAY INVISIBLE (-3100 3700);
FORCEPROP 1 LAST PATH I144
J 2
(-2773 3825);
DISPLAY 0.872340 (-2773 3825);
PAINT GREEN (-2773 3825);
DISPLAY INVISIBLE (-2773 3825);
FORCEADD TAP..6
R 2
(-2775 3925);
FORCEPROP 3 LASTPIN (-2825 3925) SIG_NAME M_D_DQS_DP<2>
J 0
(-2815 3935);
DISPLAY 0.659574 (-2815 3935);
PAINT MONO (-2815 3935);
DISPLAY INVISIBLE (-2815 3935);
FORCEPROP 1 LASTPIN (-2825 3925) BN 2
J 2
(-2773 3933);
DISPLAY 0.617021 (-2773 3933);
PAINT PINK (-2773 3933);
FORCEPROP 2 LAST CDS_LIB mstr_standard
J 0
(-2775 3925);
PAINT MONO (-2775 3925);
DISPLAY INVISIBLE (-2775 3925);
FORCEPROP 1 LAST BODY_TYPE PLUMBING
J 2
(-2775 3875);
DISPLAY 1.595745 (-2775 3875);
PAINT GREEN (-2775 3875);
DISPLAY INVISIBLE (-2775 3875);
FORCEPROP 1 LAST HDL_TAP TRUE
J 2
(-3100 3800);
DISPLAY 1.595745 (-3100 3800);
PAINT GREEN (-3100 3800);
DISPLAY INVISIBLE (-3100 3800);
FORCEPROP 1 LAST PATH I145
J 2
(-2773 3925);
DISPLAY 0.872340 (-2773 3925);
PAINT GREEN (-2773 3925);
DISPLAY INVISIBLE (-2773 3925);
FORCEADD TAP..6
R 2
(-2775 3975);
FORCEPROP 3 LASTPIN (-2825 3975) SIG_NAME M_D_DQS_DP<3>
J 0
(-2815 3985);
DISPLAY 0.659574 (-2815 3985);
PAINT MONO (-2815 3985);
DISPLAY INVISIBLE (-2815 3985);
FORCEPROP 1 LASTPIN (-2825 3975) BN 3
J 2
(-2773 3983);
DISPLAY 0.617021 (-2773 3983);
PAINT PINK (-2773 3983);
FORCEPROP 2 LAST CDS_LIB mstr_standard
J 0
(-2775 3975);
PAINT MONO (-2775 3975);
DISPLAY INVISIBLE (-2775 3975);
FORCEPROP 1 LAST BODY_TYPE PLUMBING
J 2
(-2775 3925);
DISPLAY 1.595745 (-2775 3925);
PAINT GREEN (-2775 3925);
DISPLAY INVISIBLE (-2775 3925);
FORCEPROP 1 LAST HDL_TAP TRUE
J 2
(-3100 3850);
DISPLAY 1.595745 (-3100 3850);
PAINT GREEN (-3100 3850);
DISPLAY INVISIBLE (-3100 3850);
FORCEPROP 1 LAST PATH I146
J 2
(-2773 3975);
DISPLAY 0.872340 (-2773 3975);
PAINT GREEN (-2773 3975);
DISPLAY INVISIBLE (-2773 3975);
FORCEADD OFFPAGE..2
(-1925 525);
FORCEPROP 2 LAST $XR1 50 
J 0
(-1646 525);
DISPLAY 0.638298 (-1646 525);
PAINT MONO (-1646 525);
FORCEPROP 2 LAST $XR0 49 
J 0
(-1736 525);
DISPLAY 0.638298 (-1736 525);
PAINT MONO (-1736 525);
FORCEPROP 2 LAST CDS_LIB mstr_standard
J 0
(-1925 525);
PAINT MONO (-1925 525);
DISPLAY INVISIBLE (-1925 525);
FORCEPROP 1 LAST OFFPAGE TRUE
J 0
(-1600 400);
DISPLAY 1.170213 (-1600 400);
PAINT GREEN (-1600 400);
DISPLAY INVISIBLE (-1600 400);
FORCEPROP 1 LAST COMMENT_BODY TRUE
J 0
(-1970 430);
DISPLAY 1.170213 (-1970 430);
PAINT GREEN (-1970 430);
DISPLAY INVISIBLE (-1970 430);
FORCEPROP 2 LAST PATH I147
J 0
(-1750 600);
DISPLAY 1.021277 (-1750 600);
PAINT ORANGE (-1750 600);
DISPLAY INVISIBLE (-1750 600);
FORCEADD OFFPAGE..4
(-1925 575);
FORCEPROP 2 LAST $XR1 50 
J 0
(-1649 575);
DISPLAY 0.638298 (-1649 575);
PAINT MONO (-1649 575);
FORCEPROP 2 LAST $XR0 49 
J 0
(-1739 575);
DISPLAY 0.638298 (-1739 575);
PAINT MONO (-1739 575);
FORCEPROP 2 LAST CDS_LIB mstr_standard
J 0
(-1925 575);
PAINT MONO (-1925 575);
DISPLAY INVISIBLE (-1925 575);
FORCEPROP 1 LAST OFFPAGE TRUE
J 0
(-1600 450);
DISPLAY 1.170213 (-1600 450);
PAINT GREEN (-1600 450);
DISPLAY INVISIBLE (-1600 450);
FORCEPROP 1 LAST COMMENT_BODY TRUE
J 0
(-1950 475);
DISPLAY 1.170213 (-1950 475);
PAINT GREEN (-1950 475);
DISPLAY INVISIBLE (-1950 475);
FORCEPROP 2 LAST PATH I148
J 0
(-1750 650);
DISPLAY 1.021277 (-1750 650);
PAINT ORANGE (-1750 650);
DISPLAY INVISIBLE (-1750 650);
FORCEADD OFFPAGE..2
(-1925 625);
FORCEPROP 2 LAST $XR1 50 
J 0
(-1646 625);
DISPLAY 0.638298 (-1646 625);
PAINT MONO (-1646 625);
FORCEPROP 2 LAST $XR0 49 
J 0
(-1736 625);
DISPLAY 0.638298 (-1736 625);
PAINT MONO (-1736 625);
FORCEPROP 2 LAST CDS_LIB mstr_standard
J 0
(-1925 625);
PAINT MONO (-1925 625);
DISPLAY INVISIBLE (-1925 625);
FORCEPROP 1 LAST OFFPAGE TRUE
J 0
(-1600 500);
DISPLAY 1.170213 (-1600 500);
PAINT GREEN (-1600 500);
DISPLAY INVISIBLE (-1600 500);
FORCEPROP 1 LAST COMMENT_BODY TRUE
J 0
(-1970 530);
DISPLAY 1.170213 (-1970 530);
PAINT GREEN (-1970 530);
DISPLAY INVISIBLE (-1970 530);
FORCEPROP 2 LAST PATH I149
J 0
(-1750 700);
DISPLAY 1.021277 (-1750 700);
PAINT ORANGE (-1750 700);
DISPLAY INVISIBLE (-1750 700);
FORCEADD TAP..6
(-5500 1175);
FORCEPROP 3 LASTPIN (-5450 1175) SIG_NAME M_D_ECC<2>
J 0
(-5440 1185);
DISPLAY 0.659574 (-5440 1185);
PAINT MONO (-5440 1185);
DISPLAY INVISIBLE (-5440 1185);
FORCEPROP 1 LASTPIN (-5450 1175) BN 2
J 0
(-5502 1183);
DISPLAY 0.617021 (-5502 1183);
PAINT PINK (-5502 1183);
FORCEPROP 2 LAST CDS_LIB mstr_standard
J 0
(-5500 1175);
PAINT MONO (-5500 1175);
DISPLAY INVISIBLE (-5500 1175);
FORCEPROP 1 LAST BODY_TYPE PLUMBING
J 0
(-5500 1125);
DISPLAY 1.595745 (-5500 1125);
PAINT GREEN (-5500 1125);
DISPLAY INVISIBLE (-5500 1125);
FORCEPROP 1 LAST HDL_TAP TRUE
J 0
(-5175 1050);
DISPLAY 1.595745 (-5175 1050);
PAINT GREEN (-5175 1050);
DISPLAY INVISIBLE (-5175 1050);
FORCEPROP 1 LAST PATH I15
J 0
(-5502 1175);
DISPLAY 0.872340 (-5502 1175);
PAINT GREEN (-5502 1175);
DISPLAY INVISIBLE (-5502 1175);
FORCEADD OFFPAGE..2
(-1925 825);
FORCEPROP 2 LAST $XR1 50 
J 0
(-1646 825);
DISPLAY 0.638298 (-1646 825);
PAINT MONO (-1646 825);
FORCEPROP 2 LAST $XR0 49 
J 0
(-1736 825);
DISPLAY 0.638298 (-1736 825);
PAINT MONO (-1736 825);
FORCEPROP 2 LAST CDS_LIB mstr_standard
J 0
(-1925 825);
PAINT MONO (-1925 825);
DISPLAY INVISIBLE (-1925 825);
FORCEPROP 1 LAST OFFPAGE TRUE
J 0
(-1600 700);
DISPLAY 1.170213 (-1600 700);
PAINT GREEN (-1600 700);
DISPLAY INVISIBLE (-1600 700);
FORCEPROP 1 LAST COMMENT_BODY TRUE
J 0
(-1970 730);
DISPLAY 1.170213 (-1970 730);
PAINT GREEN (-1970 730);
DISPLAY INVISIBLE (-1970 730);
FORCEPROP 2 LAST PATH I150
J 0
(-1750 900);
DISPLAY 1.021277 (-1750 900);
PAINT ORANGE (-1750 900);
DISPLAY INVISIBLE (-1750 900);
FORCEADD OFFPAGE..2
(-1925 925);
FORCEPROP 2 LAST $XR1 50 
J 0
(-1646 925);
DISPLAY 0.638298 (-1646 925);
PAINT MONO (-1646 925);
FORCEPROP 2 LAST $XR0 49 
J 0
(-1736 925);
DISPLAY 0.638298 (-1736 925);
PAINT MONO (-1736 925);
FORCEPROP 2 LAST CDS_LIB mstr_standard
J 0
(-1925 925);
PAINT MONO (-1925 925);
DISPLAY INVISIBLE (-1925 925);
FORCEPROP 1 LAST OFFPAGE TRUE
J 0
(-1600 800);
DISPLAY 1.170213 (-1600 800);
PAINT GREEN (-1600 800);
DISPLAY INVISIBLE (-1600 800);
FORCEPROP 1 LAST COMMENT_BODY TRUE
J 0
(-1970 830);
DISPLAY 1.170213 (-1970 830);
PAINT GREEN (-1970 830);
DISPLAY INVISIBLE (-1970 830);
FORCEPROP 2 LAST PATH I151
J 0
(-1750 1000);
DISPLAY 1.021277 (-1750 1000);
PAINT ORANGE (-1750 1000);
DISPLAY INVISIBLE (-1750 1000);
FORCEADD OFFPAGE..2
(-1925 1375);
FORCEPROP 2 LAST $XR1 50 
J 0
(-1646 1375);
DISPLAY 0.638298 (-1646 1375);
PAINT MONO (-1646 1375);
FORCEPROP 2 LAST $XR0 49 
J 0
(-1736 1375);
DISPLAY 0.638298 (-1736 1375);
PAINT MONO (-1736 1375);
FORCEPROP 2 LAST CDS_LIB mstr_standard
J 0
(-1925 1375);
PAINT MONO (-1925 1375);
DISPLAY INVISIBLE (-1925 1375);
FORCEPROP 1 LAST OFFPAGE TRUE
J 0
(-1600 1250);
DISPLAY 1.170213 (-1600 1250);
PAINT GREEN (-1600 1250);
DISPLAY INVISIBLE (-1600 1250);
FORCEPROP 1 LAST COMMENT_BODY TRUE
J 0
(-1970 1280);
DISPLAY 1.170213 (-1970 1280);
PAINT GREEN (-1970 1280);
DISPLAY INVISIBLE (-1970 1280);
FORCEPROP 2 LAST PATH I152
J 0
(-1750 1450);
DISPLAY 1.021277 (-1750 1450);
PAINT ORANGE (-1750 1450);
DISPLAY INVISIBLE (-1750 1450);
FORCEADD OFFPAGE..2
(-1925 1625);
FORCEPROP 2 LAST $XR1 50 
J 0
(-1646 1625);
DISPLAY 0.638298 (-1646 1625);
PAINT MONO (-1646 1625);
FORCEPROP 2 LAST $XR0 49 
J 0
(-1736 1625);
DISPLAY 0.638298 (-1736 1625);
PAINT MONO (-1736 1625);
FORCEPROP 2 LAST CDS_LIB mstr_standard
J 0
(-1925 1625);
PAINT MONO (-1925 1625);
DISPLAY INVISIBLE (-1925 1625);
FORCEPROP 1 LAST OFFPAGE TRUE
J 0
(-1600 1500);
DISPLAY 1.170213 (-1600 1500);
PAINT GREEN (-1600 1500);
DISPLAY INVISIBLE (-1600 1500);
FORCEPROP 1 LAST COMMENT_BODY TRUE
J 0
(-1970 1530);
DISPLAY 1.170213 (-1970 1530);
PAINT GREEN (-1970 1530);
DISPLAY INVISIBLE (-1970 1530);
FORCEPROP 2 LAST PATH I153
J 0
(-1750 1700);
DISPLAY 1.021277 (-1750 1700);
PAINT ORANGE (-1750 1700);
DISPLAY INVISIBLE (-1750 1700);
FORCEADD OFFPAGE..2
(-1925 1875);
FORCEPROP 2 LAST $XR1 50 
J 0
(-1646 1875);
DISPLAY 0.638298 (-1646 1875);
PAINT MONO (-1646 1875);
FORCEPROP 2 LAST $XR0 49 
J 0
(-1736 1875);
DISPLAY 0.638298 (-1736 1875);
PAINT MONO (-1736 1875);
FORCEPROP 2 LAST CDS_LIB mstr_standard
J 0
(-1925 1875);
PAINT MONO (-1925 1875);
DISPLAY INVISIBLE (-1925 1875);
FORCEPROP 1 LAST OFFPAGE TRUE
J 0
(-1600 1750);
DISPLAY 1.170213 (-1600 1750);
PAINT GREEN (-1600 1750);
DISPLAY INVISIBLE (-1600 1750);
FORCEPROP 1 LAST COMMENT_BODY TRUE
J 0
(-1970 1780);
DISPLAY 1.170213 (-1970 1780);
PAINT GREEN (-1970 1780);
DISPLAY INVISIBLE (-1970 1780);
FORCEPROP 2 LAST PATH I154
J 0
(-1750 1950);
DISPLAY 1.021277 (-1750 1950);
PAINT ORANGE (-1750 1950);
DISPLAY INVISIBLE (-1750 1950);
FORCEADD OFFPAGE..2
(-1925 2825);
FORCEPROP 2 LAST $XR1 50 
J 0
(-1646 2825);
DISPLAY 0.638298 (-1646 2825);
PAINT MONO (-1646 2825);
FORCEPROP 2 LAST $XR0 49 
J 0
(-1736 2825);
DISPLAY 0.638298 (-1736 2825);
PAINT MONO (-1736 2825);
FORCEPROP 2 LAST CDS_LIB mstr_standard
J 0
(-1925 2825);
PAINT MONO (-1925 2825);
DISPLAY INVISIBLE (-1925 2825);
FORCEPROP 1 LAST OFFPAGE TRUE
J 0
(-1600 2700);
DISPLAY 1.170213 (-1600 2700);
PAINT GREEN (-1600 2700);
DISPLAY INVISIBLE (-1600 2700);
FORCEPROP 1 LAST COMMENT_BODY TRUE
J 0
(-1970 2730);
DISPLAY 1.170213 (-1970 2730);
PAINT GREEN (-1970 2730);
DISPLAY INVISIBLE (-1970 2730);
FORCEPROP 2 LAST PATH I155
J 0
(-1750 2900);
DISPLAY 1.021277 (-1750 2900);
PAINT ORANGE (-1750 2900);
DISPLAY INVISIBLE (-1750 2900);
FORCEADD OFFPAGE..3
(-1925 3775);
FORCEPROP 2 LAST $XR1 50 
J 0
(-1621 3775);
DISPLAY 0.638298 (-1621 3775);
PAINT MONO (-1621 3775);
FORCEPROP 2 LAST $XR0 49 
J 0
(-1711 3775);
DISPLAY 0.638298 (-1711 3775);
PAINT MONO (-1711 3775);
FORCEPROP 2 LAST CDS_LIB mstr_standard
J 0
(-1925 3775);
PAINT MONO (-1925 3775);
DISPLAY INVISIBLE (-1925 3775);
FORCEPROP 1 LAST OFFPAGE TRUE
J 0
(-1600 3650);
DISPLAY 1.170213 (-1600 3650);
PAINT GREEN (-1600 3650);
DISPLAY INVISIBLE (-1600 3650);
FORCEPROP 1 LAST COMMENT_BODY TRUE
J 0
(-1975 3675);
DISPLAY 1.170213 (-1975 3675);
PAINT GREEN (-1975 3675);
DISPLAY INVISIBLE (-1975 3675);
FORCEPROP 2 LAST PATH I156
J 0
(-1725 3850);
DISPLAY 1.021277 (-1725 3850);
PAINT ORANGE (-1725 3850);
DISPLAY INVISIBLE (-1725 3850);
FORCEADD TAP..6
R 2
(-2775 4025);
FORCEPROP 3 LASTPIN (-2825 4025) SIG_NAME M_D_DQS_DP<4>
J 0
(-2815 4035);
DISPLAY 0.659574 (-2815 4035);
PAINT MONO (-2815 4035);
DISPLAY INVISIBLE (-2815 4035);
FORCEPROP 1 LASTPIN (-2825 4025) BN 4
J 2
(-2773 4033);
DISPLAY 0.617021 (-2773 4033);
PAINT PINK (-2773 4033);
FORCEPROP 2 LAST CDS_LIB mstr_standard
J 0
(-2775 4025);
PAINT MONO (-2775 4025);
DISPLAY INVISIBLE (-2775 4025);
FORCEPROP 1 LAST BODY_TYPE PLUMBING
J 2
(-2775 3975);
DISPLAY 1.595745 (-2775 3975);
PAINT GREEN (-2775 3975);
DISPLAY INVISIBLE (-2775 3975);
FORCEPROP 1 LAST HDL_TAP TRUE
J 2
(-3100 3900);
DISPLAY 1.595745 (-3100 3900);
PAINT GREEN (-3100 3900);
DISPLAY INVISIBLE (-3100 3900);
FORCEPROP 1 LAST PATH I157
J 2
(-2773 4025);
DISPLAY 0.872340 (-2773 4025);
PAINT GREEN (-2773 4025);
DISPLAY INVISIBLE (-2773 4025);
FORCEADD TAP..6
R 2
(-2775 4125);
FORCEPROP 3 LASTPIN (-2825 4125) SIG_NAME M_D_DQS_DP<6>
J 0
(-2815 4135);
DISPLAY 0.659574 (-2815 4135);
PAINT MONO (-2815 4135);
DISPLAY INVISIBLE (-2815 4135);
FORCEPROP 1 LASTPIN (-2825 4125) BN 6
J 2
(-2773 4133);
DISPLAY 0.617021 (-2773 4133);
PAINT PINK (-2773 4133);
FORCEPROP 2 LAST CDS_LIB mstr_standard
J 0
(-2775 4125);
PAINT MONO (-2775 4125);
DISPLAY INVISIBLE (-2775 4125);
FORCEPROP 1 LAST BODY_TYPE PLUMBING
J 2
(-2775 4075);
DISPLAY 1.595745 (-2775 4075);
PAINT GREEN (-2775 4075);
DISPLAY INVISIBLE (-2775 4075);
FORCEPROP 1 LAST HDL_TAP TRUE
J 2
(-3100 4000);
DISPLAY 1.595745 (-3100 4000);
PAINT GREEN (-3100 4000);
DISPLAY INVISIBLE (-3100 4000);
FORCEPROP 1 LAST PATH I158
J 2
(-2773 4125);
DISPLAY 0.872340 (-2773 4125);
PAINT GREEN (-2773 4125);
DISPLAY INVISIBLE (-2773 4125);
FORCEADD TAP..6
R 2
(-2775 4075);
FORCEPROP 3 LASTPIN (-2825 4075) SIG_NAME M_D_DQS_DP<5>
J 0
(-2815 4085);
DISPLAY 0.659574 (-2815 4085);
PAINT MONO (-2815 4085);
DISPLAY INVISIBLE (-2815 4085);
FORCEPROP 1 LASTPIN (-2825 4075) BN 5
J 2
(-2773 4083);
DISPLAY 0.617021 (-2773 4083);
PAINT PINK (-2773 4083);
FORCEPROP 2 LAST CDS_LIB mstr_standard
J 0
(-2775 4075);
PAINT MONO (-2775 4075);
DISPLAY INVISIBLE (-2775 4075);
FORCEPROP 1 LAST BODY_TYPE PLUMBING
J 2
(-2775 4025);
DISPLAY 1.595745 (-2775 4025);
PAINT GREEN (-2775 4025);
DISPLAY INVISIBLE (-2775 4025);
FORCEPROP 1 LAST HDL_TAP TRUE
J 2
(-3100 3950);
DISPLAY 1.595745 (-3100 3950);
PAINT GREEN (-3100 3950);
DISPLAY INVISIBLE (-3100 3950);
FORCEPROP 1 LAST PATH I159
J 2
(-2773 4075);
DISPLAY 0.872340 (-2773 4075);
PAINT GREEN (-2773 4075);
DISPLAY INVISIBLE (-2773 4075);
FORCEADD TAP..6
(-5500 1275);
FORCEPROP 3 LASTPIN (-5450 1275) SIG_NAME M_D_ECC<4>
J 0
(-5440 1285);
DISPLAY 0.659574 (-5440 1285);
PAINT MONO (-5440 1285);
DISPLAY INVISIBLE (-5440 1285);
FORCEPROP 1 LASTPIN (-5450 1275) BN 4
J 0
(-5502 1283);
DISPLAY 0.617021 (-5502 1283);
PAINT PINK (-5502 1283);
FORCEPROP 2 LAST CDS_LIB mstr_standard
J 0
(-5500 1275);
PAINT MONO (-5500 1275);
DISPLAY INVISIBLE (-5500 1275);
FORCEPROP 1 LAST BODY_TYPE PLUMBING
J 0
(-5500 1225);
DISPLAY 1.595745 (-5500 1225);
PAINT GREEN (-5500 1225);
DISPLAY INVISIBLE (-5500 1225);
FORCEPROP 1 LAST HDL_TAP TRUE
J 0
(-5175 1150);
DISPLAY 1.595745 (-5175 1150);
PAINT GREEN (-5175 1150);
DISPLAY INVISIBLE (-5175 1150);
FORCEPROP 1 LAST PATH I16
J 0
(-5502 1275);
DISPLAY 0.872340 (-5502 1275);
PAINT GREEN (-5502 1275);
DISPLAY INVISIBLE (-5502 1275);
FORCEADD TAP..6
R 2
(-2775 4175);
FORCEPROP 3 LASTPIN (-2825 4175) SIG_NAME M_D_DQS_DP<7>
J 0
(-2815 4185);
DISPLAY 0.659574 (-2815 4185);
PAINT MONO (-2815 4185);
DISPLAY INVISIBLE (-2815 4185);
FORCEPROP 1 LASTPIN (-2825 4175) BN 7
J 2
(-2773 4183);
DISPLAY 0.617021 (-2773 4183);
PAINT PINK (-2773 4183);
FORCEPROP 2 LAST CDS_LIB mstr_standard
J 0
(-2775 4175);
PAINT MONO (-2775 4175);
DISPLAY INVISIBLE (-2775 4175);
FORCEPROP 1 LAST BODY_TYPE PLUMBING
J 2
(-2775 4125);
DISPLAY 1.595745 (-2775 4125);
PAINT GREEN (-2775 4125);
DISPLAY INVISIBLE (-2775 4125);
FORCEPROP 1 LAST HDL_TAP TRUE
J 2
(-3100 4050);
DISPLAY 1.595745 (-3100 4050);
PAINT GREEN (-3100 4050);
DISPLAY INVISIBLE (-3100 4050);
FORCEPROP 1 LAST PATH I160
J 2
(-2773 4175);
DISPLAY 0.872340 (-2773 4175);
PAINT GREEN (-2773 4175);
DISPLAY INVISIBLE (-2773 4175);
FORCEADD TAP..6
R 2
(-2775 4275);
FORCEPROP 3 LASTPIN (-2825 4275) SIG_NAME M_D_DQS_DP<9>
J 0
(-2815 4285);
DISPLAY 0.659574 (-2815 4285);
PAINT MONO (-2815 4285);
DISPLAY INVISIBLE (-2815 4285);
FORCEPROP 1 LASTPIN (-2825 4275) BN 9
J 2
(-2773 4283);
DISPLAY 0.617021 (-2773 4283);
PAINT PINK (-2773 4283);
FORCEPROP 2 LAST CDS_LIB mstr_standard
J 0
(-2775 4275);
PAINT MONO (-2775 4275);
DISPLAY INVISIBLE (-2775 4275);
FORCEPROP 1 LAST BODY_TYPE PLUMBING
J 2
(-2775 4225);
DISPLAY 1.595745 (-2775 4225);
PAINT GREEN (-2775 4225);
DISPLAY INVISIBLE (-2775 4225);
FORCEPROP 1 LAST HDL_TAP TRUE
J 2
(-3100 4150);
DISPLAY 1.595745 (-3100 4150);
PAINT GREEN (-3100 4150);
DISPLAY INVISIBLE (-3100 4150);
FORCEPROP 1 LAST PATH I161
J 2
(-2773 4275);
DISPLAY 0.872340 (-2773 4275);
PAINT GREEN (-2773 4275);
DISPLAY INVISIBLE (-2773 4275);
FORCEADD TAP..6
R 2
(-2775 4225);
FORCEPROP 3 LASTPIN (-2825 4225) SIG_NAME M_D_DQS_DP<8>
J 0
(-2815 4235);
DISPLAY 0.659574 (-2815 4235);
PAINT MONO (-2815 4235);
DISPLAY INVISIBLE (-2815 4235);
FORCEPROP 1 LASTPIN (-2825 4225) BN 8
J 2
(-2773 4233);
DISPLAY 0.617021 (-2773 4233);
PAINT PINK (-2773 4233);
FORCEPROP 2 LAST CDS_LIB mstr_standard
J 0
(-2775 4225);
PAINT MONO (-2775 4225);
DISPLAY INVISIBLE (-2775 4225);
FORCEPROP 1 LAST BODY_TYPE PLUMBING
J 2
(-2775 4175);
DISPLAY 1.595745 (-2775 4175);
PAINT GREEN (-2775 4175);
DISPLAY INVISIBLE (-2775 4175);
FORCEPROP 1 LAST HDL_TAP TRUE
J 2
(-3100 4100);
DISPLAY 1.595745 (-3100 4100);
PAINT GREEN (-3100 4100);
DISPLAY INVISIBLE (-3100 4100);
FORCEPROP 1 LAST PATH I162
J 2
(-2773 4225);
DISPLAY 0.872340 (-2773 4225);
PAINT GREEN (-2773 4225);
DISPLAY INVISIBLE (-2773 4225);
FORCEADD TAP..6
R 2
(-2775 4325);
FORCEPROP 3 LASTPIN (-2825 4325) SIG_NAME M_D_DQS_DP<10>
J 0
(-2815 4335);
DISPLAY 0.659574 (-2815 4335);
PAINT MONO (-2815 4335);
DISPLAY INVISIBLE (-2815 4335);
FORCEPROP 1 LASTPIN (-2825 4325) BN 10
J 2
(-2773 4333);
DISPLAY 0.617021 (-2773 4333);
PAINT PINK (-2773 4333);
FORCEPROP 2 LAST CDS_LIB mstr_standard
J 0
(-2775 4325);
PAINT MONO (-2775 4325);
DISPLAY INVISIBLE (-2775 4325);
FORCEPROP 1 LAST BODY_TYPE PLUMBING
J 2
(-2775 4275);
DISPLAY 1.595745 (-2775 4275);
PAINT GREEN (-2775 4275);
DISPLAY INVISIBLE (-2775 4275);
FORCEPROP 1 LAST HDL_TAP TRUE
J 2
(-3100 4200);
DISPLAY 1.595745 (-3100 4200);
PAINT GREEN (-3100 4200);
DISPLAY INVISIBLE (-3100 4200);
FORCEPROP 1 LAST PATH I163
J 2
(-2773 4325);
DISPLAY 0.872340 (-2773 4325);
PAINT GREEN (-2773 4325);
DISPLAY INVISIBLE (-2773 4325);
FORCEADD TAP..6
R 2
(-2775 4375);
FORCEPROP 3 LASTPIN (-2825 4375) SIG_NAME M_D_DQS_DP<11>
J 0
(-2815 4385);
DISPLAY 0.659574 (-2815 4385);
PAINT MONO (-2815 4385);
DISPLAY INVISIBLE (-2815 4385);
FORCEPROP 1 LASTPIN (-2825 4375) BN 11
J 2
(-2773 4383);
DISPLAY 0.617021 (-2773 4383);
PAINT PINK (-2773 4383);
FORCEPROP 2 LAST CDS_LIB mstr_standard
J 0
(-2775 4375);
PAINT MONO (-2775 4375);
DISPLAY INVISIBLE (-2775 4375);
FORCEPROP 1 LAST BODY_TYPE PLUMBING
J 2
(-2775 4325);
DISPLAY 1.595745 (-2775 4325);
PAINT GREEN (-2775 4325);
DISPLAY INVISIBLE (-2775 4325);
FORCEPROP 1 LAST HDL_TAP TRUE
J 2
(-3100 4250);
DISPLAY 1.595745 (-3100 4250);
PAINT GREEN (-3100 4250);
DISPLAY INVISIBLE (-3100 4250);
FORCEPROP 1 LAST PATH I164
J 2
(-2773 4375);
DISPLAY 0.872340 (-2773 4375);
PAINT GREEN (-2773 4375);
DISPLAY INVISIBLE (-2773 4375);
FORCEADD TAP..6
R 2
(-2775 4425);
FORCEPROP 3 LASTPIN (-2825 4425) SIG_NAME M_D_DQS_DP<12>
J 0
(-2815 4435);
DISPLAY 0.659574 (-2815 4435);
PAINT MONO (-2815 4435);
DISPLAY INVISIBLE (-2815 4435);
FORCEPROP 1 LASTPIN (-2825 4425) BN 12
J 2
(-2773 4433);
DISPLAY 0.617021 (-2773 4433);
PAINT PINK (-2773 4433);
FORCEPROP 2 LAST CDS_LIB mstr_standard
J 0
(-2775 4425);
PAINT MONO (-2775 4425);
DISPLAY INVISIBLE (-2775 4425);
FORCEPROP 1 LAST BODY_TYPE PLUMBING
J 2
(-2775 4375);
DISPLAY 1.595745 (-2775 4375);
PAINT GREEN (-2775 4375);
DISPLAY INVISIBLE (-2775 4375);
FORCEPROP 1 LAST HDL_TAP TRUE
J 2
(-3100 4300);
DISPLAY 1.595745 (-3100 4300);
PAINT GREEN (-3100 4300);
DISPLAY INVISIBLE (-3100 4300);
FORCEPROP 1 LAST PATH I165
J 2
(-2773 4425);
DISPLAY 0.872340 (-2773 4425);
PAINT GREEN (-2773 4425);
DISPLAY INVISIBLE (-2773 4425);
FORCEADD TAP..6
R 2
(-2775 4525);
FORCEPROP 3 LASTPIN (-2825 4525) SIG_NAME M_D_DQS_DP<14>
J 0
(-2815 4535);
DISPLAY 0.659574 (-2815 4535);
PAINT MONO (-2815 4535);
DISPLAY INVISIBLE (-2815 4535);
FORCEPROP 1 LASTPIN (-2825 4525) BN 14
J 2
(-2773 4533);
DISPLAY 0.617021 (-2773 4533);
PAINT PINK (-2773 4533);
FORCEPROP 2 LAST CDS_LIB mstr_standard
J 0
(-2775 4525);
PAINT MONO (-2775 4525);
DISPLAY INVISIBLE (-2775 4525);
FORCEPROP 1 LAST BODY_TYPE PLUMBING
J 2
(-2775 4475);
DISPLAY 1.595745 (-2775 4475);
PAINT GREEN (-2775 4475);
DISPLAY INVISIBLE (-2775 4475);
FORCEPROP 1 LAST HDL_TAP TRUE
J 2
(-3100 4400);
DISPLAY 1.595745 (-3100 4400);
PAINT GREEN (-3100 4400);
DISPLAY INVISIBLE (-3100 4400);
FORCEPROP 1 LAST PATH I166
J 2
(-2773 4525);
DISPLAY 0.872340 (-2773 4525);
PAINT GREEN (-2773 4525);
DISPLAY INVISIBLE (-2773 4525);
FORCEADD TAP..6
R 2
(-2775 4475);
FORCEPROP 3 LASTPIN (-2825 4475) SIG_NAME M_D_DQS_DP<13>
J 0
(-2815 4485);
DISPLAY 0.659574 (-2815 4485);
PAINT MONO (-2815 4485);
DISPLAY INVISIBLE (-2815 4485);
FORCEPROP 1 LASTPIN (-2825 4475) BN 13
J 2
(-2773 4483);
DISPLAY 0.617021 (-2773 4483);
PAINT PINK (-2773 4483);
FORCEPROP 2 LAST CDS_LIB mstr_standard
J 0
(-2775 4475);
PAINT MONO (-2775 4475);
DISPLAY INVISIBLE (-2775 4475);
FORCEPROP 1 LAST BODY_TYPE PLUMBING
J 2
(-2775 4425);
DISPLAY 1.595745 (-2775 4425);
PAINT GREEN (-2775 4425);
DISPLAY INVISIBLE (-2775 4425);
FORCEPROP 1 LAST HDL_TAP TRUE
J 2
(-3100 4350);
DISPLAY 1.595745 (-3100 4350);
PAINT GREEN (-3100 4350);
DISPLAY INVISIBLE (-3100 4350);
FORCEPROP 1 LAST PATH I167
J 2
(-2773 4475);
DISPLAY 0.872340 (-2773 4475);
PAINT GREEN (-2773 4475);
DISPLAY INVISIBLE (-2773 4475);
FORCEADD TAP..6
R 2
(-2775 4625);
FORCEPROP 3 LASTPIN (-2825 4625) SIG_NAME M_D_DQS_DP<16>
J 0
(-2815 4635);
DISPLAY 0.659574 (-2815 4635);
PAINT MONO (-2815 4635);
DISPLAY INVISIBLE (-2815 4635);
FORCEPROP 1 LASTPIN (-2825 4625) BN 16
J 2
(-2773 4633);
DISPLAY 0.617021 (-2773 4633);
PAINT PINK (-2773 4633);
FORCEPROP 2 LAST CDS_LIB mstr_standard
J 0
(-2775 4625);
PAINT MONO (-2775 4625);
DISPLAY INVISIBLE (-2775 4625);
FORCEPROP 1 LAST BODY_TYPE PLUMBING
J 2
(-2775 4575);
DISPLAY 1.595745 (-2775 4575);
PAINT GREEN (-2775 4575);
DISPLAY INVISIBLE (-2775 4575);
FORCEPROP 1 LAST HDL_TAP TRUE
J 2
(-3100 4500);
DISPLAY 1.595745 (-3100 4500);
PAINT GREEN (-3100 4500);
DISPLAY INVISIBLE (-3100 4500);
FORCEPROP 1 LAST PATH I168
J 2
(-2773 4625);
DISPLAY 0.872340 (-2773 4625);
PAINT GREEN (-2773 4625);
DISPLAY INVISIBLE (-2773 4625);
FORCEADD TAP..6
R 2
(-2775 4575);
FORCEPROP 3 LASTPIN (-2825 4575) SIG_NAME M_D_DQS_DP<15>
J 0
(-2815 4585);
DISPLAY 0.659574 (-2815 4585);
PAINT MONO (-2815 4585);
DISPLAY INVISIBLE (-2815 4585);
FORCEPROP 1 LASTPIN (-2825 4575) BN 15
J 2
(-2773 4583);
DISPLAY 0.617021 (-2773 4583);
PAINT PINK (-2773 4583);
FORCEPROP 2 LAST CDS_LIB mstr_standard
J 0
(-2775 4575);
PAINT MONO (-2775 4575);
DISPLAY INVISIBLE (-2775 4575);
FORCEPROP 1 LAST BODY_TYPE PLUMBING
J 2
(-2775 4525);
DISPLAY 1.595745 (-2775 4525);
PAINT GREEN (-2775 4525);
DISPLAY INVISIBLE (-2775 4525);
FORCEPROP 1 LAST HDL_TAP TRUE
J 2
(-3100 4450);
DISPLAY 1.595745 (-3100 4450);
PAINT GREEN (-3100 4450);
DISPLAY INVISIBLE (-3100 4450);
FORCEPROP 1 LAST PATH I169
J 2
(-2773 4575);
DISPLAY 0.872340 (-2773 4575);
PAINT GREEN (-2773 4575);
DISPLAY INVISIBLE (-2773 4575);
FORCEADD TAP..6
(-5500 1225);
FORCEPROP 3 LASTPIN (-5450 1225) SIG_NAME M_D_ECC<3>
J 0
(-5440 1235);
DISPLAY 0.659574 (-5440 1235);
PAINT MONO (-5440 1235);
DISPLAY INVISIBLE (-5440 1235);
FORCEPROP 1 LASTPIN (-5450 1225) BN 3
J 0
(-5502 1233);
DISPLAY 0.617021 (-5502 1233);
PAINT PINK (-5502 1233);
FORCEPROP 2 LAST CDS_LIB mstr_standard
J 0
(-5500 1225);
PAINT MONO (-5500 1225);
DISPLAY INVISIBLE (-5500 1225);
FORCEPROP 1 LAST BODY_TYPE PLUMBING
J 0
(-5500 1175);
DISPLAY 1.595745 (-5500 1175);
PAINT GREEN (-5500 1175);
DISPLAY INVISIBLE (-5500 1175);
FORCEPROP 1 LAST HDL_TAP TRUE
J 0
(-5175 1100);
DISPLAY 1.595745 (-5175 1100);
PAINT GREEN (-5175 1100);
DISPLAY INVISIBLE (-5175 1100);
FORCEPROP 1 LAST PATH I17
J 0
(-5502 1225);
DISPLAY 0.872340 (-5502 1225);
PAINT GREEN (-5502 1225);
DISPLAY INVISIBLE (-5502 1225);
FORCEADD TAP..6
R 2
(-2775 4675);
FORCEPROP 3 LASTPIN (-2825 4675) SIG_NAME M_D_DQS_DP<17>
J 0
(-2815 4685);
DISPLAY 0.659574 (-2815 4685);
PAINT MONO (-2815 4685);
DISPLAY INVISIBLE (-2815 4685);
FORCEPROP 1 LASTPIN (-2825 4675) BN 17
J 2
(-2773 4683);
DISPLAY 0.617021 (-2773 4683);
PAINT PINK (-2773 4683);
FORCEPROP 2 LAST CDS_LIB mstr_standard
J 2
(-2775 4675);
PAINT MONO (-2775 4675);
DISPLAY INVISIBLE (-2775 4675);
FORCEPROP 1 LAST BODY_TYPE PLUMBING
J 2
(-2775 4625);
DISPLAY 1.595745 (-2775 4625);
PAINT GREEN (-2775 4625);
DISPLAY INVISIBLE (-2775 4625);
FORCEPROP 1 LAST HDL_TAP TRUE
J 2
(-3100 4550);
DISPLAY 1.595745 (-3100 4550);
PAINT GREEN (-3100 4550);
DISPLAY INVISIBLE (-3100 4550);
FORCEPROP 1 LAST PATH I170
J 2
(-2773 4675);
DISPLAY 0.872340 (-2773 4675);
PAINT GREEN (-2773 4675);
DISPLAY INVISIBLE (-2773 4675);
FORCEADD OFFPAGE..3
(-1925 4750);
FORCEPROP 2 LAST $XR1 50 
J 0
(-1621 4750);
DISPLAY 0.638298 (-1621 4750);
PAINT MONO (-1621 4750);
FORCEPROP 2 LAST $XR0 49 
J 0
(-1711 4750);
DISPLAY 0.638298 (-1711 4750);
PAINT MONO (-1711 4750);
FORCEPROP 2 LAST CDS_LIB mstr_standard
J 0
(-1925 4750);
PAINT MONO (-1925 4750);
DISPLAY INVISIBLE (-1925 4750);
FORCEPROP 1 LAST OFFPAGE TRUE
J 0
(-1600 4625);
DISPLAY 1.170213 (-1600 4625);
PAINT GREEN (-1600 4625);
DISPLAY INVISIBLE (-1600 4625);
FORCEPROP 1 LAST COMMENT_BODY TRUE
J 0
(-1975 4650);
DISPLAY 1.170213 (-1975 4650);
PAINT GREEN (-1975 4650);
DISPLAY INVISIBLE (-1975 4650);
FORCEPROP 2 LAST PATH I171
J 0
(-1725 4825);
DISPLAY 1.021277 (-1725 4825);
PAINT ORANGE (-1725 4825);
DISPLAY INVISIBLE (-1725 4825);
FORCEADD SKX_EXT_B..6
(-4100 2575);
FORCEPROP 1 LAST LOCATION U5D1
J 0
(-4900 4925);
DISPLAY 0.617021 (-4900 4925);
PAINT AQUA (-4900 4925);
FORCEPROP 1 LAST PART_NUMBER TBD
J 0
(-4900 325);
DISPLAY 0.617021 (-4900 325);
PAINT BLUE (-4900 325);
FORCEPROP 1 LAST MATERIAL IC
J 0
(-4900 4875);
DISPLAY 0.617021 (-4900 4875);
PAINT SKYBLUE (-4900 4875);
FORCEPROP 2 LASTPIN (-3250 525) $PN ED53
J 0
(-3240 535);
DISPLAY 0.617021 (-3240 535);
PAINT ORANGE (-3240 535);
FORCEPROP 2 LASTPIN (-3250 1575) $PN EA48
J 0
(-3240 1585);
DISPLAY 0.617021 (-3240 1585);
PAINT ORANGE (-3240 1585);
FORCEPROP 2 LASTPIN (-3250 1525) $PN EA50
J 0
(-3240 1535);
DISPLAY 0.617021 (-3240 1535);
PAINT ORANGE (-3240 1535);
FORCEPROP 2 LASTPIN (-3250 1475) $PN EE48
J 0
(-3240 1485);
DISPLAY 0.617021 (-3240 1485);
PAINT ORANGE (-3240 1485);
FORCEPROP 2 LASTPIN (-3250 1425) $PN EE50
J 0
(-3240 1435);
DISPLAY 0.617021 (-3240 1435);
PAINT ORANGE (-3240 1435);
FORCEPROP 2 LASTPIN (-3250 2775) $PN EA46
J 0
(-3240 2785);
DISPLAY 0.617021 (-3240 2785);
PAINT ORANGE (-3240 2785);
FORCEPROP 2 LASTPIN (-3250 2725) $PN EA52
J 0
(-3240 2735);
DISPLAY 0.617021 (-3240 2735);
PAINT ORANGE (-3240 2735);
FORCEPROP 2 LASTPIN (-3250 2675) $PN DV49
J 0
(-3240 2685);
DISPLAY 0.617021 (-3240 2685);
PAINT ORANGE (-3240 2685);
FORCEPROP 2 LASTPIN (-3250 2625) $PN ED51
J 0
(-3240 2635);
DISPLAY 0.617021 (-3240 2635);
PAINT ORANGE (-3240 2635);
FORCEPROP 2 LASTPIN (-3250 2575) $PN DW48
J 0
(-3240 2585);
DISPLAY 0.617021 (-3240 2585);
PAINT ORANGE (-3240 2585);
FORCEPROP 2 LASTPIN (-3250 2525) $PN DT63
J 0
(-3240 2535);
DISPLAY 0.617021 (-3240 2535);
PAINT ORANGE (-3240 2535);
FORCEPROP 2 LASTPIN (-3250 2475) $PN EB61
J 0
(-3240 2485);
DISPLAY 0.617021 (-3240 2485);
PAINT ORANGE (-3240 2485);
FORCEPROP 2 LASTPIN (-3250 2425) $PN DW54
J 0
(-3240 2435);
DISPLAY 0.617021 (-3240 2435);
PAINT ORANGE (-3240 2435);
FORCEPROP 2 LASTPIN (-3250 2375) $PN EF61
J 0
(-3240 2385);
DISPLAY 0.617021 (-3240 2385);
PAINT ORANGE (-3240 2385);
FORCEPROP 2 LASTPIN (-3250 2325) $PN EB59
J 0
(-3240 2335);
DISPLAY 0.617021 (-3240 2335);
PAINT ORANGE (-3240 2335);
FORCEPROP 2 LASTPIN (-3250 2275) $PN EA60
J 0
(-3240 2285);
DISPLAY 0.617021 (-3240 2285);
PAINT ORANGE (-3240 2285);
FORCEPROP 2 LASTPIN (-3250 2225) $PN EE60
J 0
(-3240 2235);
DISPLAY 0.617021 (-3240 2235);
PAINT ORANGE (-3240 2235);
FORCEPROP 2 LASTPIN (-3250 2175) $PN EA58
J 0
(-3240 2185);
DISPLAY 0.617021 (-3240 2185);
PAINT ORANGE (-3240 2185);
FORCEPROP 2 LASTPIN (-3250 2125) $PN ED59
J 0
(-3240 2135);
DISPLAY 0.617021 (-3240 2135);
PAINT ORANGE (-3240 2135);
FORCEPROP 2 LASTPIN (-3250 2075) $PN EB57
J 0
(-3240 2085);
DISPLAY 0.617021 (-3240 2085);
PAINT ORANGE (-3240 2085);
FORCEPROP 2 LASTPIN (-3250 2025) $PN EE58
J 0
(-3240 2035);
DISPLAY 0.617021 (-3240 2035);
PAINT ORANGE (-3240 2035);
FORCEPROP 2 LASTPIN (-3250 1975) $PN ED57
J 0
(-3240 1985);
DISPLAY 0.617021 (-3240 1985);
PAINT ORANGE (-3240 1985);
FORCEPROP 2 LASTPIN (-3250 1925) $PN EB53
J 0
(-3240 1935);
DISPLAY 0.617021 (-3240 1935);
PAINT ORANGE (-3240 1935);
FORCEPROP 2 LASTPIN (-4950 1425) $PN DE66
J 2
(-4960 1435);
DISPLAY 0.617021 (-4960 1435);
PAINT ORANGE (-4960 1435);
FORCEPROP 2 LASTPIN (-4950 1375) $PN DA66
J 2
(-4960 1385);
DISPLAY 0.617021 (-4960 1385);
PAINT ORANGE (-4960 1385);
FORCEPROP 2 LASTPIN (-4950 1325) $PN DD69
J 2
(-4960 1335);
DISPLAY 0.617021 (-4960 1335);
PAINT ORANGE (-4960 1335);
FORCEPROP 2 LASTPIN (-4950 1275) $PN DB69
J 2
(-4960 1285);
DISPLAY 0.617021 (-4960 1285);
PAINT ORANGE (-4960 1285);
FORCEPROP 2 LASTPIN (-4950 1225) $PN DD65
J 2
(-4960 1235);
DISPLAY 0.617021 (-4960 1235);
PAINT ORANGE (-4960 1235);
FORCEPROP 2 LASTPIN (-4950 1175) $PN DB65
J 2
(-4960 1185);
DISPLAY 0.617021 (-4960 1185);
PAINT ORANGE (-4960 1185);
FORCEPROP 2 LASTPIN (-4950 1125) $PN DE68
J 2
(-4960 1135);
DISPLAY 0.617021 (-4960 1135);
PAINT ORANGE (-4960 1135);
FORCEPROP 2 LASTPIN (-4950 1075) $PN DA68
J 2
(-4960 1085);
DISPLAY 0.617021 (-4960 1085);
PAINT ORANGE (-4960 1085);
FORCEPROP 2 LASTPIN (-3250 4675) $PN CY67
J 0
(-3240 4685);
DISPLAY 0.617021 (-3240 4685);
PAINT ORANGE (-3240 4685);
FORCEPROP 2 LASTPIN (-3250 4625) $PN DP23
J 0
(-3240 4635);
DISPLAY 0.617021 (-3240 4635);
PAINT ORANGE (-3240 4635);
FORCEPROP 2 LASTPIN (-3250 4575) $PN DP29
J 0
(-3240 4585);
DISPLAY 0.617021 (-3240 4585);
PAINT ORANGE (-3240 4585);
FORCEPROP 2 LASTPIN (-3250 4525) $PN DM35
J 0
(-3240 4535);
DISPLAY 0.617021 (-3240 4535);
PAINT ORANGE (-3240 4535);
FORCEPROP 2 LASTPIN (-3250 4475) $PN DW38
J 0
(-3240 4485);
DISPLAY 0.617021 (-3240 4485);
PAINT ORANGE (-3240 4485);
FORCEPROP 2 LASTPIN (-3250 4425) $PN DM75
J 0
(-3240 4435);
DISPLAY 0.617021 (-3240 4435);
PAINT ORANGE (-3240 4435);
FORCEPROP 2 LASTPIN (-3250 4375) $PN DP79
J 0
(-3240 4385);
DISPLAY 0.617021 (-3240 4385);
PAINT ORANGE (-3240 4385);
FORCEPROP 2 LASTPIN (-3250 4325) $PN DL84
J 0
(-3240 4335);
DISPLAY 0.617021 (-3240 4335);
PAINT ORANGE (-3240 4335);
FORCEPROP 2 LASTPIN (-3250 4275) $PN CP85
J 0
(-3240 4285);
DISPLAY 0.617021 (-3240 4285);
PAINT ORANGE (-3240 4285);
FORCEPROP 2 LASTPIN (-3250 4225) $PN DD67
J 0
(-3240 4235);
DISPLAY 0.617021 (-3240 4235);
PAINT ORANGE (-3240 4235);
FORCEPROP 2 LASTPIN (-3250 4175) $PN DT23
J 0
(-3240 4185);
DISPLAY 0.617021 (-3240 4185);
PAINT ORANGE (-3240 4185);
FORCEPROP 2 LASTPIN (-3250 4125) $PN DT29
J 0
(-3240 4135);
DISPLAY 0.617021 (-3240 4135);
PAINT ORANGE (-3240 4135);
FORCEPROP 2 LASTPIN (-3250 4075) $PN DT35
J 0
(-3240 4085);
DISPLAY 0.617021 (-3240 4085);
PAINT ORANGE (-3240 4085);
FORCEPROP 2 LASTPIN (-3250 4025) $PN EC38
J 0
(-3240 4035);
DISPLAY 0.617021 (-3240 4035);
PAINT ORANGE (-3240 4035);
FORCEPROP 2 LASTPIN (-3250 3975) $PN DT75
J 0
(-3240 3985);
DISPLAY 0.617021 (-3240 3985);
PAINT ORANGE (-3240 3985);
FORCEPROP 2 LASTPIN (-3250 3925) $PN DM81
J 0
(-3240 3935);
DISPLAY 0.617021 (-3240 3935);
PAINT ORANGE (-3240 3935);
FORCEPROP 2 LASTPIN (-3250 3875) $PN DP85
J 0
(-3240 3885);
DISPLAY 0.617021 (-3240 3885);
PAINT ORANGE (-3240 3885);
FORCEPROP 2 LASTPIN (-3250 3825) $PN CV85
J 0
(-3240 3835);
DISPLAY 0.617021 (-3240 3835);
PAINT ORANGE (-3240 3835);
FORCEPROP 2 LASTPIN (-3250 3725) $PN DB67
J 0
(-3240 3735);
DISPLAY 0.617021 (-3240 3735);
PAINT ORANGE (-3240 3735);
FORCEPROP 2 LASTPIN (-3250 3675) $PN DM23
J 0
(-3240 3685);
DISPLAY 0.617021 (-3240 3685);
PAINT ORANGE (-3240 3685);
FORCEPROP 2 LASTPIN (-3250 3625) $PN DM29
J 0
(-3240 3635);
DISPLAY 0.617021 (-3240 3635);
PAINT ORANGE (-3240 3635);
FORCEPROP 2 LASTPIN (-3250 3575) $PN DP35
J 0
(-3240 3585);
DISPLAY 0.617021 (-3240 3585);
PAINT ORANGE (-3240 3585);
FORCEPROP 2 LASTPIN (-3250 3525) $PN EA38
J 0
(-3240 3535);
DISPLAY 0.617021 (-3240 3535);
PAINT ORANGE (-3240 3535);
FORCEPROP 2 LASTPIN (-3250 3475) $PN DP75
J 0
(-3240 3485);
DISPLAY 0.617021 (-3240 3485);
PAINT ORANGE (-3240 3485);
FORCEPROP 2 LASTPIN (-3250 3425) $PN DN80
J 0
(-3240 3435);
DISPLAY 0.617021 (-3240 3435);
PAINT ORANGE (-3240 3435);
FORCEPROP 2 LASTPIN (-3250 3375) $PN DM85
J 0
(-3240 3385);
DISPLAY 0.617021 (-3240 3385);
PAINT ORANGE (-3240 3385);
FORCEPROP 2 LASTPIN (-3250 3325) $PN CR84
J 0
(-3240 3335);
DISPLAY 0.617021 (-3240 3335);
PAINT ORANGE (-3240 3335);
FORCEPROP 2 LASTPIN (-3250 3275) $PN DF67
J 0
(-3240 3285);
DISPLAY 0.617021 (-3240 3285);
PAINT ORANGE (-3240 3285);
FORCEPROP 2 LASTPIN (-3250 3225) $PN DV23
J 0
(-3240 3235);
DISPLAY 0.617021 (-3240 3235);
PAINT ORANGE (-3240 3235);
FORCEPROP 2 LASTPIN (-3250 3175) $PN DV29
J 0
(-3240 3185);
DISPLAY 0.617021 (-3240 3185);
PAINT ORANGE (-3240 3185);
FORCEPROP 2 LASTPIN (-3250 3125) $PN DV35
J 0
(-3240 3135);
DISPLAY 0.617021 (-3240 3135);
PAINT ORANGE (-3240 3135);
FORCEPROP 2 LASTPIN (-3250 3075) $PN EE38
J 0
(-3240 3085);
DISPLAY 0.617021 (-3240 3085);
PAINT ORANGE (-3240 3085);
FORCEPROP 2 LASTPIN (-3250 3025) $PN DV75
J 0
(-3240 3035);
DISPLAY 0.617021 (-3240 3035);
PAINT ORANGE (-3240 3035);
FORCEPROP 2 LASTPIN (-3250 2975) $PN DL82
J 0
(-3240 2985);
DISPLAY 0.617021 (-3240 2985);
PAINT ORANGE (-3240 2985);
FORCEPROP 2 LASTPIN (-3250 2925) $PN DN84
J 0
(-3240 2935);
DISPLAY 0.617021 (-3240 2935);
PAINT ORANGE (-3240 2935);
FORCEPROP 2 LASTPIN (-3250 2875) $PN CU84
J 0
(-3240 2885);
DISPLAY 0.617021 (-3240 2885);
PAINT ORANGE (-3240 2885);
FORCEPROP 2 LASTPIN (-4950 4675) $PN DW22
J 2
(-4960 4685);
DISPLAY 0.617021 (-4960 4685);
PAINT ORANGE (-4960 4685);
FORCEPROP 2 LASTPIN (-4950 4625) $PN EC22
J 2
(-4960 4635);
DISPLAY 0.617021 (-4960 4635);
PAINT ORANGE (-4960 4635);
FORCEPROP 2 LASTPIN (-4950 4575) $PN DT25
J 2
(-4960 4585);
DISPLAY 0.617021 (-4960 4585);
PAINT ORANGE (-4960 4585);
FORCEPROP 2 LASTPIN (-4950 4525) $PN DP25
J 2
(-4960 4535);
DISPLAY 0.617021 (-4960 4535);
PAINT ORANGE (-4960 4535);
FORCEPROP 2 LASTPIN (-4950 4475) $PN EB21
J 2
(-4960 4485);
DISPLAY 0.617021 (-4960 4485);
PAINT ORANGE (-4960 4485);
FORCEPROP 2 LASTPIN (-4950 4425) $PN DY21
J 2
(-4960 4435);
DISPLAY 0.617021 (-4960 4435);
PAINT ORANGE (-4960 4435);
FORCEPROP 2 LASTPIN (-4950 4375) $PN DU24
J 2
(-4960 4385);
DISPLAY 0.617021 (-4960 4385);
PAINT ORANGE (-4960 4385);
FORCEPROP 2 LASTPIN (-4950 4325) $PN DN24
J 2
(-4960 4335);
DISPLAY 0.617021 (-4960 4335);
PAINT ORANGE (-4960 4335);
FORCEPROP 2 LASTPIN (-4950 4275) $PN DU28
J 2
(-4960 4285);
DISPLAY 0.617021 (-4960 4285);
PAINT ORANGE (-4960 4285);
FORCEPROP 2 LASTPIN (-4950 4225) $PN DN28
J 2
(-4960 4235);
DISPLAY 0.617021 (-4960 4235);
PAINT ORANGE (-4960 4235);
FORCEPROP 2 LASTPIN (-4950 4175) $PN DT31
J 2
(-4960 4185);
DISPLAY 0.617021 (-4960 4185);
PAINT ORANGE (-4960 4185);
FORCEPROP 2 LASTPIN (-4950 4125) $PN DP31
J 2
(-4960 4135);
DISPLAY 0.617021 (-4960 4135);
PAINT ORANGE (-4960 4135);
FORCEPROP 2 LASTPIN (-4950 4075) $PN DT27
J 2
(-4960 4085);
DISPLAY 0.617021 (-4960 4085);
PAINT ORANGE (-4960 4085);
FORCEPROP 2 LASTPIN (-4950 4025) $PN DP27
J 2
(-4960 4035);
DISPLAY 0.617021 (-4960 4035);
PAINT ORANGE (-4960 4035);
FORCEPROP 2 LASTPIN (-4950 3975) $PN DU30
J 2
(-4960 3985);
DISPLAY 0.617021 (-4960 3985);
PAINT ORANGE (-4960 3985);
FORCEPROP 2 LASTPIN (-4950 3875) $PN DU34
J 2
(-4960 3885);
DISPLAY 0.617021 (-4960 3885);
PAINT ORANGE (-4960 3885);
FORCEPROP 2 LASTPIN (-4950 3825) $PN DN34
J 2
(-4960 3835);
DISPLAY 0.617021 (-4960 3835);
PAINT ORANGE (-4960 3835);
FORCEPROP 2 LASTPIN (-4950 3775) $PN DT37
J 2
(-4960 3785);
DISPLAY 0.617021 (-4960 3785);
PAINT ORANGE (-4960 3785);
FORCEPROP 2 LASTPIN (-4950 3725) $PN DP37
J 2
(-4960 3735);
DISPLAY 0.617021 (-4960 3735);
PAINT ORANGE (-4960 3735);
FORCEPROP 2 LASTPIN (-4950 3675) $PN DT33
J 2
(-4960 3685);
DISPLAY 0.617021 (-4960 3685);
PAINT ORANGE (-4960 3685);
FORCEPROP 2 LASTPIN (-4950 3625) $PN DP33
J 2
(-4960 3635);
DISPLAY 0.617021 (-4960 3635);
PAINT ORANGE (-4960 3635);
FORCEPROP 2 LASTPIN (-4950 3575) $PN DU36
J 2
(-4960 3585);
DISPLAY 0.617021 (-4960 3585);
PAINT ORANGE (-4960 3585);
FORCEPROP 2 LASTPIN (-4950 3525) $PN DN36
J 2
(-4960 3535);
DISPLAY 0.617021 (-4960 3535);
PAINT ORANGE (-4960 3535);
FORCEPROP 2 LASTPIN (-4950 3475) $PN ED37
J 2
(-4960 3485);
DISPLAY 0.617021 (-4960 3485);
PAINT ORANGE (-4960 3485);
FORCEPROP 2 LASTPIN (-4950 3425) $PN DY37
J 2
(-4960 3435);
DISPLAY 0.617021 (-4960 3435);
PAINT ORANGE (-4960 3435);
FORCEPROP 2 LASTPIN (-4950 3375) $PN EA40
J 2
(-4960 3385);
DISPLAY 0.617021 (-4960 3385);
PAINT ORANGE (-4960 3385);
FORCEPROP 2 LASTPIN (-4950 3325) $PN DY39
J 2
(-4960 3335);
DISPLAY 0.617021 (-4960 3335);
PAINT ORANGE (-4960 3335);
FORCEPROP 2 LASTPIN (-4950 3275) $PN EC36
J 2
(-4960 3285);
DISPLAY 0.617021 (-4960 3285);
PAINT ORANGE (-4960 3285);
FORCEPROP 2 LASTPIN (-4950 3225) $PN EA36
J 2
(-4960 3235);
DISPLAY 0.617021 (-4960 3235);
PAINT ORANGE (-4960 3235);
FORCEPROP 2 LASTPIN (-4950 3175) $PN ED39
J 2
(-4960 3185);
DISPLAY 0.617021 (-4960 3185);
PAINT ORANGE (-4960 3185);
FORCEPROP 2 LASTPIN (-4950 3125) $PN EC40
J 2
(-4960 3135);
DISPLAY 0.617021 (-4960 3135);
PAINT ORANGE (-4960 3135);
FORCEPROP 2 LASTPIN (-4950 3025) $PN DN74
J 2
(-4960 3035);
DISPLAY 0.617021 (-4960 3035);
PAINT ORANGE (-4960 3035);
FORCEPROP 2 LASTPIN (-4950 2975) $PN DT77
J 2
(-4960 2985);
DISPLAY 0.617021 (-4960 2985);
PAINT ORANGE (-4960 2985);
FORCEPROP 2 LASTPIN (-4950 2925) $PN DP77
J 2
(-4960 2935);
DISPLAY 0.617021 (-4960 2935);
PAINT ORANGE (-4960 2935);
FORCEPROP 2 LASTPIN (-4950 2875) $PN DT73
J 2
(-4960 2885);
DISPLAY 0.617021 (-4960 2885);
PAINT ORANGE (-4960 2885);
FORCEPROP 2 LASTPIN (-4950 2825) $PN DP73
J 2
(-4960 2835);
DISPLAY 0.617021 (-4960 2835);
PAINT ORANGE (-4960 2835);
FORCEPROP 2 LASTPIN (-4950 2775) $PN DU76
J 2
(-4960 2785);
DISPLAY 0.617021 (-4960 2785);
PAINT ORANGE (-4960 2785);
FORCEPROP 2 LASTPIN (-4950 2725) $PN DN76
J 2
(-4960 2735);
DISPLAY 0.617021 (-4960 2735);
PAINT ORANGE (-4960 2735);
FORCEPROP 2 LASTPIN (-4950 2675) $PN DN82
J 2
(-4960 2685);
DISPLAY 0.617021 (-4960 2685);
PAINT ORANGE (-4960 2685);
FORCEPROP 2 LASTPIN (-4950 2625) $PN DR80
J 2
(-4960 2635);
DISPLAY 0.617021 (-4960 2635);
PAINT ORANGE (-4960 2635);
FORCEPROP 2 LASTPIN (-4950 2575) $PN DJ80
J 2
(-4960 2585);
DISPLAY 0.617021 (-4960 2585);
PAINT ORANGE (-4960 2585);
FORCEPROP 2 LASTPIN (-4950 2525) $PN DK79
J 2
(-4960 2535);
DISPLAY 0.617021 (-4960 2535);
PAINT ORANGE (-4960 2535);
FORCEPROP 2 LASTPIN (-4950 2475) $PN DR82
J 2
(-4960 2485);
DISPLAY 0.617021 (-4960 2485);
PAINT ORANGE (-4960 2485);
FORCEPROP 2 LASTPIN (-4950 2425) $PN DT81
J 2
(-4960 2435);
DISPLAY 0.617021 (-4960 2435);
PAINT ORANGE (-4960 2435);
FORCEPROP 2 LASTPIN (-4950 2375) $PN DK81
J 2
(-4960 2385);
DISPLAY 0.617021 (-4960 2385);
PAINT ORANGE (-4960 2385);
FORCEPROP 2 LASTPIN (-4950 2325) $PN DM79
J 2
(-4960 2335);
DISPLAY 0.617021 (-4960 2335);
PAINT ORANGE (-4960 2335);
FORCEPROP 2 LASTPIN (-4950 2275) $PN DV85
J 2
(-4960 2285);
DISPLAY 0.617021 (-4960 2285);
PAINT ORANGE (-4960 2285);
FORCEPROP 2 LASTPIN (-4950 2225) $PN DR84
J 2
(-4960 2235);
DISPLAY 0.617021 (-4960 2235);
PAINT ORANGE (-4960 2235);
FORCEPROP 2 LASTPIN (-4950 2175) $PN DE84
J 2
(-4960 2185);
DISPLAY 0.617021 (-4960 2185);
PAINT ORANGE (-4960 2185);
FORCEPROP 2 LASTPIN (-4950 2125) $PN DD85
J 2
(-4960 2135);
DISPLAY 0.617021 (-4960 2135);
PAINT ORANGE (-4960 2135);
FORCEPROP 2 LASTPIN (-4950 2075) $PN DY83
J 2
(-4960 2085);
DISPLAY 0.617021 (-4960 2085);
PAINT ORANGE (-4960 2085);
FORCEPROP 2 LASTPIN (-4950 2025) $PN DV83
J 2
(-4960 2035);
DISPLAY 0.617021 (-4960 2035);
PAINT ORANGE (-4960 2035);
FORCEPROP 2 LASTPIN (-4950 1975) $PN DH85
J 2
(-4960 1985);
DISPLAY 0.617021 (-4960 1985);
PAINT ORANGE (-4960 1985);
FORCEPROP 2 LASTPIN (-4950 1925) $PN DG84
J 2
(-4960 1935);
DISPLAY 0.617021 (-4960 1935);
PAINT ORANGE (-4960 1935);
FORCEPROP 2 LASTPIN (-4950 1875) $PN CW84
J 2
(-4960 1885);
DISPLAY 0.617021 (-4960 1885);
PAINT ORANGE (-4960 1885);
FORCEPROP 2 LASTPIN (-4950 1825) $PN CW86
J 2
(-4960 1835);
DISPLAY 0.617021 (-4960 1835);
PAINT ORANGE (-4960 1835);
FORCEPROP 2 LASTPIN (-4950 1775) $PN CL86
J 2
(-4960 1785);
DISPLAY 0.617021 (-4960 1785);
PAINT ORANGE (-4960 1785);
FORCEPROP 2 LASTPIN (-4950 1725) $PN CL84
J 2
(-4960 1735);
DISPLAY 0.617021 (-4960 1735);
PAINT ORANGE (-4960 1735);
FORCEPROP 2 LASTPIN (-4950 1675) $PN DA84
J 2
(-4960 1685);
DISPLAY 0.617021 (-4960 1685);
PAINT ORANGE (-4960 1685);
FORCEPROP 2 LASTPIN (-4950 1625) $PN DA86
J 2
(-4960 1635);
DISPLAY 0.617021 (-4960 1635);
PAINT ORANGE (-4960 1635);
FORCEPROP 2 LASTPIN (-4950 1575) $PN CN86
J 2
(-4960 1585);
DISPLAY 0.617021 (-4960 1585);
PAINT ORANGE (-4960 1585);
FORCEPROP 2 LASTPIN (-4950 1525) $PN CN84
J 2
(-4960 1535);
DISPLAY 0.617021 (-4960 1535);
PAINT ORANGE (-4960 1535);
FORCEPROP 2 LASTPIN (-3250 1325) $PN EB45
J 0
(-3240 1335);
DISPLAY 0.617021 (-3240 1335);
PAINT ORANGE (-3240 1335);
FORCEPROP 2 LASTPIN (-3250 1275) $PN DV45
J 0
(-3240 1285);
DISPLAY 0.617021 (-3240 1285);
PAINT ORANGE (-3240 1285);
FORCEPROP 2 LASTPIN (-3250 1225) $PN EB49
J 0
(-3240 1235);
DISPLAY 0.617021 (-3240 1235);
PAINT ORANGE (-3240 1235);
FORCEPROP 2 LASTPIN (-3250 1175) $PN EB51
J 0
(-3240 1185);
DISPLAY 0.617021 (-3240 1185);
PAINT ORANGE (-3240 1185);
FORCEPROP 2 LASTPIN (-3250 1125) $PN EB47
J 0
(-3240 1135);
DISPLAY 0.617021 (-3240 1135);
PAINT ORANGE (-3240 1135);
FORCEPROP 2 LASTPIN (-3250 1075) $PN ED47
J 0
(-3240 1085);
DISPLAY 0.617021 (-3240 1085);
PAINT ORANGE (-3240 1085);
FORCEPROP 2 LASTPIN (-3250 1025) $PN ED49
J 0
(-3240 1035);
DISPLAY 0.617021 (-3240 1035);
PAINT ORANGE (-3240 1035);
FORCEPROP 2 LASTPIN (-3250 975) $PN EF51
J 0
(-3240 985);
DISPLAY 0.617021 (-3240 985);
PAINT ORANGE (-3240 985);
FORCEPROP 2 LASTPIN (-4950 975) $PN EE56
J 2
(-4960 985);
DISPLAY 0.617021 (-4960 985);
PAINT ORANGE (-4960 985);
FORCEPROP 2 LASTPIN (-4950 925) $PN EA56
J 2
(-4960 935);
DISPLAY 0.617021 (-4960 935);
PAINT ORANGE (-4960 935);
FORCEPROP 2 LASTPIN (-4950 875) $PN EE54
J 2
(-4960 885);
DISPLAY 0.617021 (-4960 885);
PAINT ORANGE (-4960 885);
FORCEPROP 2 LASTPIN (-4950 825) $PN EB55
J 2
(-4960 835);
DISPLAY 0.617021 (-4960 835);
PAINT ORANGE (-4960 835);
FORCEPROP 2 LASTPIN (-4950 775) $PN EF57
J 2
(-4960 785);
DISPLAY 0.617021 (-4960 785);
PAINT ORANGE (-4960 785);
FORCEPROP 2 LASTPIN (-4950 725) $PN DW56
J 2
(-4960 735);
DISPLAY 0.617021 (-4960 735);
PAINT ORANGE (-4960 735);
FORCEPROP 2 LASTPIN (-4950 675) $PN EF55
J 2
(-4960 685);
DISPLAY 0.617021 (-4960 685);
PAINT ORANGE (-4960 685);
FORCEPROP 2 LASTPIN (-4950 625) $PN ED55
J 2
(-4960 635);
DISPLAY 0.617021 (-4960 635);
PAINT ORANGE (-4960 635);
FORCEPROP 2 LASTPIN (-3250 1825) $PN EB63
J 0
(-3240 1835);
DISPLAY 0.617021 (-3240 1835);
PAINT ORANGE (-3240 1835);
FORCEPROP 2 LASTPIN (-3250 1775) $PN EA62
J 0
(-3240 1785);
DISPLAY 0.617021 (-3240 1785);
PAINT ORANGE (-3240 1785);
FORCEPROP 2 LASTPIN (-3250 1725) $PN EF63
J 0
(-3240 1735);
DISPLAY 0.617021 (-3240 1735);
PAINT ORANGE (-3240 1735);
FORCEPROP 2 LASTPIN (-3250 1675) $PN EE62
J 0
(-3240 1685);
DISPLAY 0.617021 (-3240 1685);
PAINT ORANGE (-3240 1685);
FORCEPROP 2 LASTPIN (-4950 525) $PN DV47
J 2
(-4960 535);
DISPLAY 0.617021 (-4960 535);
PAINT ORANGE (-4960 535);
FORCEPROP 2 LASTPIN (-3250 875) $PN DW62
J 0
(-3240 885);
DISPLAY 0.617021 (-3240 885);
PAINT ORANGE (-3240 885);
FORCEPROP 2 LASTPIN (-3250 825) $PN ED61
J 0
(-3240 835);
DISPLAY 0.617021 (-3240 835);
PAINT ORANGE (-3240 835);
FORCEPROP 2 LASTPIN (-3250 775) $PN EA54
J 0
(-3240 785);
DISPLAY 0.617021 (-3240 785);
PAINT ORANGE (-3240 785);
FORCEPROP 2 LASTPIN (-3250 725) $PN EE52
J 0
(-3240 735);
DISPLAY 0.617021 (-3240 735);
PAINT ORANGE (-3240 735);
FORCEPROP 2 LASTPIN (-3250 575) $PN ED63
J 0
(-3240 585);
DISPLAY 0.617021 (-3240 585);
PAINT ORANGE (-3240 585);
FORCEPROP 2 LASTPIN (-3250 625) $PN DW60
J 0
(-3240 635);
DISPLAY 0.617021 (-3240 635);
PAINT ORANGE (-3240 635);
FORCEPROP 2 LASTPIN (-4950 3075) $PN DU74
J 2
(-4960 3085);
DISPLAY 0.617021 (-4960 3085);
PAINT ORANGE (-4960 3085);
FORCEPROP 2 LASTPIN (-4950 3925) $PN DN30
J 2
(-4960 3935);
DISPLAY 0.617021 (-4960 3935);
PAINT ORANGE (-4960 3935);
FORCEPROP 1 LAST PACK_TYPE BGA1
J 0
(-4900 4975);
PAINT SKYBLUE (-4900 4975);
DISPLAY INVISIBLE (-4900 4975);
FORCEPROP 2 LAST CDS_LIB chpset_lib
J 0
(-4100 2575);
PAINT ORANGE (-4100 2575);
DISPLAY INVISIBLE (-4100 2575);
FORCEPROP 2 LAST SEC_TYPE BGA1
J 0
(-4900 4975);
DISPLAY 1.021277 (-4900 4975);
PAINT ORANGE (-4900 4975);
DISPLAY INVISIBLE (-4900 4975);
FORCEPROP 2 LAST SEC 6
J 0
(-4900 4975);
DISPLAY 0.680851 (-4900 4975);
PAINT MONO (-4900 4975);
DISPLAY INVISIBLE (-4900 4975);
FORCEPROP 2 LAST CDS_LOCATION U5D1
J 0
(-4900 4925);
DISPLAY 0.617021 (-4900 4925);
PAINT AQUA (-4900 4925);
DISPLAY INVISIBLE (-4900 4925);
FORCEPROP 1 LAST PATH I172
J 0
(-4100 4875);
PAINT GREEN (-4100 4875);
DISPLAY INVISIBLE (-4100 4875);
FORCEPROP 0 LAST ROOM CPU0
J 0
(-4900 5025);
DISPLAY 1.021277 (-4900 5025);
PAINT ORANGE (-4900 5025);
DISPLAY INVISIBLE (-4900 5025);
FORCEADD TAP..6
(-5500 1325);
FORCEPROP 3 LASTPIN (-5450 1325) SIG_NAME M_D_ECC<5>
J 0
(-5440 1335);
DISPLAY 0.659574 (-5440 1335);
PAINT MONO (-5440 1335);
DISPLAY INVISIBLE (-5440 1335);
FORCEPROP 1 LASTPIN (-5450 1325) BN 5
J 0
(-5502 1333);
DISPLAY 0.617021 (-5502 1333);
PAINT PINK (-5502 1333);
FORCEPROP 2 LAST CDS_LIB mstr_standard
J 0
(-5500 1325);
PAINT MONO (-5500 1325);
DISPLAY INVISIBLE (-5500 1325);
FORCEPROP 1 LAST BODY_TYPE PLUMBING
J 0
(-5500 1275);
DISPLAY 1.595745 (-5500 1275);
PAINT GREEN (-5500 1275);
DISPLAY INVISIBLE (-5500 1275);
FORCEPROP 1 LAST HDL_TAP TRUE
J 0
(-5175 1200);
DISPLAY 1.595745 (-5175 1200);
PAINT GREEN (-5175 1200);
DISPLAY INVISIBLE (-5175 1200);
FORCEPROP 1 LAST PATH I18
J 0
(-5502 1325);
DISPLAY 0.872340 (-5502 1325);
PAINT GREEN (-5502 1325);
DISPLAY INVISIBLE (-5502 1325);
FORCEADD TAP..6
(-5500 1375);
FORCEPROP 3 LASTPIN (-5450 1375) SIG_NAME M_D_ECC<6>
J 0
(-5440 1385);
DISPLAY 0.659574 (-5440 1385);
PAINT MONO (-5440 1385);
DISPLAY INVISIBLE (-5440 1385);
FORCEPROP 1 LASTPIN (-5450 1375) BN 6
J 0
(-5502 1383);
DISPLAY 0.617021 (-5502 1383);
PAINT PINK (-5502 1383);
FORCEPROP 2 LAST CDS_LIB mstr_standard
J 0
(-5500 1375);
PAINT MONO (-5500 1375);
DISPLAY INVISIBLE (-5500 1375);
FORCEPROP 1 LAST BODY_TYPE PLUMBING
J 0
(-5500 1325);
DISPLAY 1.595745 (-5500 1325);
PAINT GREEN (-5500 1325);
DISPLAY INVISIBLE (-5500 1325);
FORCEPROP 1 LAST HDL_TAP TRUE
J 0
(-5175 1250);
DISPLAY 1.595745 (-5175 1250);
PAINT GREEN (-5175 1250);
DISPLAY INVISIBLE (-5175 1250);
FORCEPROP 1 LAST PATH I19
J 0
(-5502 1375);
DISPLAY 0.872340 (-5502 1375);
PAINT GREEN (-5502 1375);
DISPLAY INVISIBLE (-5502 1375);
FORCEADD OFFPAGE..5
(-6350 825);
FORCEPROP 2 LAST $XR1 50 
J 0
(-6664 825);
DISPLAY 0.638298 (-6664 825);
PAINT MONO (-6664 825);
FORCEPROP 2 LAST $XR0 49 
J 0
(-6574 825);
DISPLAY 0.638298 (-6574 825);
PAINT MONO (-6574 825);
FORCEPROP 2 LAST CDS_LIB mstr_standard
J 0
(-6350 825);
PAINT MONO (-6350 825);
DISPLAY INVISIBLE (-6350 825);
FORCEPROP 1 LAST OFFPAGE TRUE
J 0
(-6025 700);
DISPLAY 1.170213 (-6025 700);
PAINT GREEN (-6025 700);
DISPLAY INVISIBLE (-6025 700);
FORCEPROP 1 LAST COMMENT_BODY TRUE
J 0
(-6250 750);
DISPLAY 1.170213 (-6250 750);
PAINT GREEN (-6250 750);
DISPLAY INVISIBLE (-6250 750);
FORCEPROP 2 LAST PATH I2
J 0
(-6300 900);
DISPLAY 1.021277 (-6300 900);
PAINT ORANGE (-6300 900);
DISPLAY INVISIBLE (-6300 900);
FORCEADD TAP..6
(-5500 1425);
FORCEPROP 3 LASTPIN (-5450 1425) SIG_NAME M_D_ECC<7>
J 0
(-5440 1435);
DISPLAY 0.659574 (-5440 1435);
PAINT MONO (-5440 1435);
DISPLAY INVISIBLE (-5440 1435);
FORCEPROP 1 LASTPIN (-5450 1425) BN 7
J 0
(-5502 1433);
DISPLAY 0.617021 (-5502 1433);
PAINT PINK (-5502 1433);
FORCEPROP 2 LAST CDS_LIB mstr_standard
J 0
(-5500 1425);
PAINT MONO (-5500 1425);
DISPLAY INVISIBLE (-5500 1425);
FORCEPROP 1 LAST BODY_TYPE PLUMBING
J 0
(-5500 1375);
DISPLAY 1.595745 (-5500 1375);
PAINT GREEN (-5500 1375);
DISPLAY INVISIBLE (-5500 1375);
FORCEPROP 1 LAST HDL_TAP TRUE
J 0
(-5175 1300);
DISPLAY 1.595745 (-5175 1300);
PAINT GREEN (-5175 1300);
DISPLAY INVISIBLE (-5175 1300);
FORCEPROP 1 LAST PATH I20
J 0
(-5502 1425);
DISPLAY 0.872340 (-5502 1425);
PAINT GREEN (-5502 1425);
DISPLAY INVISIBLE (-5502 1425);
FORCEADD TAP..6
(-5500 1525);
FORCEPROP 3 LASTPIN (-5450 1525) SIG_NAME M_D_DQ<0>
J 0
(-5440 1535);
DISPLAY 0.659574 (-5440 1535);
PAINT MONO (-5440 1535);
DISPLAY INVISIBLE (-5440 1535);
FORCEPROP 1 LASTPIN (-5450 1525) BN 0
J 0
(-5502 1533);
DISPLAY 0.617021 (-5502 1533);
PAINT PINK (-5502 1533);
FORCEPROP 2 LAST CDS_LIB mstr_standard
J 0
(-5500 1525);
PAINT MONO (-5500 1525);
DISPLAY INVISIBLE (-5500 1525);
FORCEPROP 1 LAST BODY_TYPE PLUMBING
J 0
(-5500 1475);
DISPLAY 1.595745 (-5500 1475);
PAINT GREEN (-5500 1475);
DISPLAY INVISIBLE (-5500 1475);
FORCEPROP 1 LAST HDL_TAP TRUE
J 0
(-5175 1400);
DISPLAY 1.595745 (-5175 1400);
PAINT GREEN (-5175 1400);
DISPLAY INVISIBLE (-5175 1400);
FORCEPROP 1 LAST PATH I21
J 0
(-5502 1525);
DISPLAY 0.872340 (-5502 1525);
PAINT GREEN (-5502 1525);
DISPLAY INVISIBLE (-5502 1525);
FORCEADD TAP..6
(-5500 1575);
FORCEPROP 3 LASTPIN (-5450 1575) SIG_NAME M_D_DQ<1>
J 0
(-5440 1585);
DISPLAY 0.659574 (-5440 1585);
PAINT MONO (-5440 1585);
DISPLAY INVISIBLE (-5440 1585);
FORCEPROP 1 LASTPIN (-5450 1575) BN 1
J 0
(-5502 1583);
DISPLAY 0.617021 (-5502 1583);
PAINT PINK (-5502 1583);
FORCEPROP 2 LAST CDS_LIB mstr_standard
J 0
(-5500 1575);
PAINT MONO (-5500 1575);
DISPLAY INVISIBLE (-5500 1575);
FORCEPROP 1 LAST BODY_TYPE PLUMBING
J 0
(-5500 1525);
DISPLAY 1.595745 (-5500 1525);
PAINT GREEN (-5500 1525);
DISPLAY INVISIBLE (-5500 1525);
FORCEPROP 1 LAST HDL_TAP TRUE
J 0
(-5175 1450);
DISPLAY 1.595745 (-5175 1450);
PAINT GREEN (-5175 1450);
DISPLAY INVISIBLE (-5175 1450);
FORCEPROP 1 LAST PATH I22
J 0
(-5502 1575);
DISPLAY 0.872340 (-5502 1575);
PAINT GREEN (-5502 1575);
DISPLAY INVISIBLE (-5502 1575);
FORCEADD TAP..6
(-5500 1625);
FORCEPROP 3 LASTPIN (-5450 1625) SIG_NAME M_D_DQ<2>
J 0
(-5440 1635);
DISPLAY 0.659574 (-5440 1635);
PAINT MONO (-5440 1635);
DISPLAY INVISIBLE (-5440 1635);
FORCEPROP 1 LASTPIN (-5450 1625) BN 2
J 0
(-5502 1633);
DISPLAY 0.617021 (-5502 1633);
PAINT PINK (-5502 1633);
FORCEPROP 2 LAST CDS_LIB mstr_standard
J 0
(-5500 1625);
PAINT MONO (-5500 1625);
DISPLAY INVISIBLE (-5500 1625);
FORCEPROP 1 LAST BODY_TYPE PLUMBING
J 0
(-5500 1575);
DISPLAY 1.595745 (-5500 1575);
PAINT GREEN (-5500 1575);
DISPLAY INVISIBLE (-5500 1575);
FORCEPROP 1 LAST HDL_TAP TRUE
J 0
(-5175 1500);
DISPLAY 1.595745 (-5175 1500);
PAINT GREEN (-5175 1500);
DISPLAY INVISIBLE (-5175 1500);
FORCEPROP 1 LAST PATH I23
J 0
(-5502 1625);
DISPLAY 0.872340 (-5502 1625);
PAINT GREEN (-5502 1625);
DISPLAY INVISIBLE (-5502 1625);
FORCEADD TAP..6
(-5500 1675);
FORCEPROP 3 LASTPIN (-5450 1675) SIG_NAME M_D_DQ<3>
J 0
(-5440 1685);
DISPLAY 0.659574 (-5440 1685);
PAINT MONO (-5440 1685);
DISPLAY INVISIBLE (-5440 1685);
FORCEPROP 1 LASTPIN (-5450 1675) BN 3
J 0
(-5502 1683);
DISPLAY 0.617021 (-5502 1683);
PAINT PINK (-5502 1683);
FORCEPROP 2 LAST CDS_LIB mstr_standard
J 0
(-5500 1675);
PAINT MONO (-5500 1675);
DISPLAY INVISIBLE (-5500 1675);
FORCEPROP 1 LAST BODY_TYPE PLUMBING
J 0
(-5500 1625);
DISPLAY 1.595745 (-5500 1625);
PAINT GREEN (-5500 1625);
DISPLAY INVISIBLE (-5500 1625);
FORCEPROP 1 LAST HDL_TAP TRUE
J 0
(-5175 1550);
DISPLAY 1.595745 (-5175 1550);
PAINT GREEN (-5175 1550);
DISPLAY INVISIBLE (-5175 1550);
FORCEPROP 1 LAST PATH I24
J 0
(-5502 1675);
DISPLAY 0.872340 (-5502 1675);
PAINT GREEN (-5502 1675);
DISPLAY INVISIBLE (-5502 1675);
FORCEADD TAP..6
(-5500 1725);
FORCEPROP 3 LASTPIN (-5450 1725) SIG_NAME M_D_DQ<4>
J 0
(-5440 1735);
DISPLAY 0.659574 (-5440 1735);
PAINT MONO (-5440 1735);
DISPLAY INVISIBLE (-5440 1735);
FORCEPROP 1 LASTPIN (-5450 1725) BN 4
J 0
(-5502 1733);
DISPLAY 0.617021 (-5502 1733);
PAINT PINK (-5502 1733);
FORCEPROP 2 LAST CDS_LIB mstr_standard
J 0
(-5500 1725);
PAINT MONO (-5500 1725);
DISPLAY INVISIBLE (-5500 1725);
FORCEPROP 1 LAST BODY_TYPE PLUMBING
J 0
(-5500 1675);
DISPLAY 1.595745 (-5500 1675);
PAINT GREEN (-5500 1675);
DISPLAY INVISIBLE (-5500 1675);
FORCEPROP 1 LAST HDL_TAP TRUE
J 0
(-5175 1600);
DISPLAY 1.595745 (-5175 1600);
PAINT GREEN (-5175 1600);
DISPLAY INVISIBLE (-5175 1600);
FORCEPROP 1 LAST PATH I25
J 0
(-5502 1725);
DISPLAY 0.872340 (-5502 1725);
PAINT GREEN (-5502 1725);
DISPLAY INVISIBLE (-5502 1725);
FORCEADD TAP..6
(-5500 1775);
FORCEPROP 3 LASTPIN (-5450 1775) SIG_NAME M_D_DQ<5>
J 0
(-5440 1785);
DISPLAY 0.659574 (-5440 1785);
PAINT MONO (-5440 1785);
DISPLAY INVISIBLE (-5440 1785);
FORCEPROP 1 LASTPIN (-5450 1775) BN 5
J 0
(-5502 1783);
DISPLAY 0.617021 (-5502 1783);
PAINT PINK (-5502 1783);
FORCEPROP 2 LAST CDS_LIB mstr_standard
J 0
(-5500 1775);
PAINT MONO (-5500 1775);
DISPLAY INVISIBLE (-5500 1775);
FORCEPROP 1 LAST BODY_TYPE PLUMBING
J 0
(-5500 1725);
DISPLAY 1.595745 (-5500 1725);
PAINT GREEN (-5500 1725);
DISPLAY INVISIBLE (-5500 1725);
FORCEPROP 1 LAST HDL_TAP TRUE
J 0
(-5175 1650);
DISPLAY 1.595745 (-5175 1650);
PAINT GREEN (-5175 1650);
DISPLAY INVISIBLE (-5175 1650);
FORCEPROP 1 LAST PATH I26
J 0
(-5502 1775);
DISPLAY 0.872340 (-5502 1775);
PAINT GREEN (-5502 1775);
DISPLAY INVISIBLE (-5502 1775);
FORCEADD TAP..6
(-5500 1825);
FORCEPROP 3 LASTPIN (-5450 1825) SIG_NAME M_D_DQ<6>
J 0
(-5440 1835);
DISPLAY 0.659574 (-5440 1835);
PAINT MONO (-5440 1835);
DISPLAY INVISIBLE (-5440 1835);
FORCEPROP 1 LASTPIN (-5450 1825) BN 6
J 0
(-5502 1833);
DISPLAY 0.617021 (-5502 1833);
PAINT PINK (-5502 1833);
FORCEPROP 2 LAST CDS_LIB mstr_standard
J 0
(-5500 1825);
PAINT MONO (-5500 1825);
DISPLAY INVISIBLE (-5500 1825);
FORCEPROP 1 LAST BODY_TYPE PLUMBING
J 0
(-5500 1775);
DISPLAY 1.595745 (-5500 1775);
PAINT GREEN (-5500 1775);
DISPLAY INVISIBLE (-5500 1775);
FORCEPROP 1 LAST HDL_TAP TRUE
J 0
(-5175 1700);
DISPLAY 1.595745 (-5175 1700);
PAINT GREEN (-5175 1700);
DISPLAY INVISIBLE (-5175 1700);
FORCEPROP 1 LAST PATH I27
J 0
(-5502 1825);
DISPLAY 0.872340 (-5502 1825);
PAINT GREEN (-5502 1825);
DISPLAY INVISIBLE (-5502 1825);
FORCEADD TAP..6
(-5500 1925);
FORCEPROP 3 LASTPIN (-5450 1925) SIG_NAME M_D_DQ<8>
J 0
(-5440 1935);
DISPLAY 0.659574 (-5440 1935);
PAINT MONO (-5440 1935);
DISPLAY INVISIBLE (-5440 1935);
FORCEPROP 1 LASTPIN (-5450 1925) BN 8
J 0
(-5502 1933);
DISPLAY 0.617021 (-5502 1933);
PAINT PINK (-5502 1933);
FORCEPROP 2 LAST CDS_LIB mstr_standard
J 0
(-5500 1925);
PAINT MONO (-5500 1925);
DISPLAY INVISIBLE (-5500 1925);
FORCEPROP 1 LAST BODY_TYPE PLUMBING
J 0
(-5500 1875);
DISPLAY 1.595745 (-5500 1875);
PAINT GREEN (-5500 1875);
DISPLAY INVISIBLE (-5500 1875);
FORCEPROP 1 LAST HDL_TAP TRUE
J 0
(-5175 1800);
DISPLAY 1.595745 (-5175 1800);
PAINT GREEN (-5175 1800);
DISPLAY INVISIBLE (-5175 1800);
FORCEPROP 1 LAST PATH I28
J 0
(-5502 1925);
DISPLAY 0.872340 (-5502 1925);
PAINT GREEN (-5502 1925);
DISPLAY INVISIBLE (-5502 1925);
FORCEADD TAP..6
(-5500 1875);
FORCEPROP 3 LASTPIN (-5450 1875) SIG_NAME M_D_DQ<7>
J 0
(-5440 1885);
DISPLAY 0.659574 (-5440 1885);
PAINT MONO (-5440 1885);
DISPLAY INVISIBLE (-5440 1885);
FORCEPROP 1 LASTPIN (-5450 1875) BN 7
J 0
(-5502 1883);
DISPLAY 0.617021 (-5502 1883);
PAINT PINK (-5502 1883);
FORCEPROP 2 LAST CDS_LIB mstr_standard
J 0
(-5500 1875);
PAINT MONO (-5500 1875);
DISPLAY INVISIBLE (-5500 1875);
FORCEPROP 1 LAST BODY_TYPE PLUMBING
J 0
(-5500 1825);
DISPLAY 1.595745 (-5500 1825);
PAINT GREEN (-5500 1825);
DISPLAY INVISIBLE (-5500 1825);
FORCEPROP 1 LAST HDL_TAP TRUE
J 0
(-5175 1750);
DISPLAY 1.595745 (-5175 1750);
PAINT GREEN (-5175 1750);
DISPLAY INVISIBLE (-5175 1750);
FORCEPROP 1 LAST PATH I29
J 0
(-5502 1875);
DISPLAY 0.872340 (-5502 1875);
PAINT GREEN (-5502 1875);
DISPLAY INVISIBLE (-5502 1875);
FORCEADD OFFPAGE..5
(-6350 1025);
FORCEPROP 2 LAST $XR1 50 
J 0
(-6664 1025);
DISPLAY 0.638298 (-6664 1025);
PAINT MONO (-6664 1025);
FORCEPROP 2 LAST $XR0 49 
J 0
(-6574 1025);
DISPLAY 0.638298 (-6574 1025);
PAINT MONO (-6574 1025);
FORCEPROP 2 LAST CDS_LIB mstr_standard
J 0
(-6350 1025);
PAINT MONO (-6350 1025);
DISPLAY INVISIBLE (-6350 1025);
FORCEPROP 1 LAST OFFPAGE TRUE
J 0
(-6025 900);
DISPLAY 1.170213 (-6025 900);
PAINT GREEN (-6025 900);
DISPLAY INVISIBLE (-6025 900);
FORCEPROP 1 LAST COMMENT_BODY TRUE
J 0
(-6250 950);
DISPLAY 1.170213 (-6250 950);
PAINT GREEN (-6250 950);
DISPLAY INVISIBLE (-6250 950);
FORCEPROP 2 LAST PATH I3
J 0
(-6300 1100);
DISPLAY 1.021277 (-6300 1100);
PAINT ORANGE (-6300 1100);
DISPLAY INVISIBLE (-6300 1100);
FORCEADD TAP..6
(-5500 1975);
FORCEPROP 3 LASTPIN (-5450 1975) SIG_NAME M_D_DQ<9>
J 0
(-5440 1985);
DISPLAY 0.659574 (-5440 1985);
PAINT MONO (-5440 1985);
DISPLAY INVISIBLE (-5440 1985);
FORCEPROP 1 LASTPIN (-5450 1975) BN 9
J 0
(-5502 1983);
DISPLAY 0.617021 (-5502 1983);
PAINT PINK (-5502 1983);
FORCEPROP 2 LAST CDS_LIB mstr_standard
J 0
(-5500 1975);
PAINT MONO (-5500 1975);
DISPLAY INVISIBLE (-5500 1975);
FORCEPROP 1 LAST BODY_TYPE PLUMBING
J 0
(-5500 1925);
DISPLAY 1.595745 (-5500 1925);
PAINT GREEN (-5500 1925);
DISPLAY INVISIBLE (-5500 1925);
FORCEPROP 1 LAST HDL_TAP TRUE
J 0
(-5175 1850);
DISPLAY 1.595745 (-5175 1850);
PAINT GREEN (-5175 1850);
DISPLAY INVISIBLE (-5175 1850);
FORCEPROP 1 LAST PATH I31
J 0
(-5502 1975);
DISPLAY 0.872340 (-5502 1975);
PAINT GREEN (-5502 1975);
DISPLAY INVISIBLE (-5502 1975);
FORCEADD TAP..6
(-5500 2025);
FORCEPROP 3 LASTPIN (-5450 2025) SIG_NAME M_D_DQ<10>
J 0
(-5440 2035);
DISPLAY 0.659574 (-5440 2035);
PAINT MONO (-5440 2035);
DISPLAY INVISIBLE (-5440 2035);
FORCEPROP 1 LASTPIN (-5450 2025) BN 10
J 0
(-5502 2033);
DISPLAY 0.617021 (-5502 2033);
PAINT PINK (-5502 2033);
FORCEPROP 2 LAST CDS_LIB mstr_standard
J 0
(-5500 2025);
PAINT MONO (-5500 2025);
DISPLAY INVISIBLE (-5500 2025);
FORCEPROP 1 LAST BODY_TYPE PLUMBING
J 0
(-5500 1975);
DISPLAY 1.595745 (-5500 1975);
PAINT GREEN (-5500 1975);
DISPLAY INVISIBLE (-5500 1975);
FORCEPROP 1 LAST HDL_TAP TRUE
J 0
(-5175 1900);
DISPLAY 1.595745 (-5175 1900);
PAINT GREEN (-5175 1900);
DISPLAY INVISIBLE (-5175 1900);
FORCEPROP 1 LAST PATH I32
J 0
(-5502 2025);
DISPLAY 0.872340 (-5502 2025);
PAINT GREEN (-5502 2025);
DISPLAY INVISIBLE (-5502 2025);
FORCEADD TAP..6
(-5500 2075);
FORCEPROP 3 LASTPIN (-5450 2075) SIG_NAME M_D_DQ<11>
J 0
(-5440 2085);
DISPLAY 0.659574 (-5440 2085);
PAINT MONO (-5440 2085);
DISPLAY INVISIBLE (-5440 2085);
FORCEPROP 1 LASTPIN (-5450 2075) BN 11
J 0
(-5502 2083);
DISPLAY 0.617021 (-5502 2083);
PAINT PINK (-5502 2083);
FORCEPROP 2 LAST CDS_LIB mstr_standard
J 0
(-5500 2075);
PAINT MONO (-5500 2075);
DISPLAY INVISIBLE (-5500 2075);
FORCEPROP 1 LAST BODY_TYPE PLUMBING
J 0
(-5500 2025);
DISPLAY 1.595745 (-5500 2025);
PAINT GREEN (-5500 2025);
DISPLAY INVISIBLE (-5500 2025);
FORCEPROP 1 LAST HDL_TAP TRUE
J 0
(-5175 1950);
DISPLAY 1.595745 (-5175 1950);
PAINT GREEN (-5175 1950);
DISPLAY INVISIBLE (-5175 1950);
FORCEPROP 1 LAST PATH I33
J 0
(-5502 2075);
DISPLAY 0.872340 (-5502 2075);
PAINT GREEN (-5502 2075);
DISPLAY INVISIBLE (-5502 2075);
FORCEADD TAP..6
(-5500 2125);
FORCEPROP 3 LASTPIN (-5450 2125) SIG_NAME M_D_DQ<12>
J 0
(-5440 2135);
DISPLAY 0.659574 (-5440 2135);
PAINT MONO (-5440 2135);
DISPLAY INVISIBLE (-5440 2135);
FORCEPROP 1 LASTPIN (-5450 2125) BN 12
J 0
(-5502 2133);
DISPLAY 0.617021 (-5502 2133);
PAINT PINK (-5502 2133);
FORCEPROP 2 LAST CDS_LIB mstr_standard
J 0
(-5500 2125);
PAINT MONO (-5500 2125);
DISPLAY INVISIBLE (-5500 2125);
FORCEPROP 1 LAST BODY_TYPE PLUMBING
J 0
(-5500 2075);
DISPLAY 1.595745 (-5500 2075);
PAINT GREEN (-5500 2075);
DISPLAY INVISIBLE (-5500 2075);
FORCEPROP 1 LAST HDL_TAP TRUE
J 0
(-5175 2000);
DISPLAY 1.595745 (-5175 2000);
PAINT GREEN (-5175 2000);
DISPLAY INVISIBLE (-5175 2000);
FORCEPROP 1 LAST PATH I34
J 0
(-5502 2125);
DISPLAY 0.872340 (-5502 2125);
PAINT GREEN (-5502 2125);
DISPLAY INVISIBLE (-5502 2125);
FORCEADD TAP..6
(-5500 2175);
FORCEPROP 3 LASTPIN (-5450 2175) SIG_NAME M_D_DQ<13>
J 0
(-5440 2185);
DISPLAY 0.659574 (-5440 2185);
PAINT MONO (-5440 2185);
DISPLAY INVISIBLE (-5440 2185);
FORCEPROP 1 LASTPIN (-5450 2175) BN 13
J 0
(-5502 2183);
DISPLAY 0.617021 (-5502 2183);
PAINT PINK (-5502 2183);
FORCEPROP 2 LAST CDS_LIB mstr_standard
J 0
(-5500 2175);
PAINT MONO (-5500 2175);
DISPLAY INVISIBLE (-5500 2175);
FORCEPROP 1 LAST BODY_TYPE PLUMBING
J 0
(-5500 2125);
DISPLAY 1.595745 (-5500 2125);
PAINT GREEN (-5500 2125);
DISPLAY INVISIBLE (-5500 2125);
FORCEPROP 1 LAST HDL_TAP TRUE
J 0
(-5175 2050);
DISPLAY 1.595745 (-5175 2050);
PAINT GREEN (-5175 2050);
DISPLAY INVISIBLE (-5175 2050);
FORCEPROP 1 LAST PATH I35
J 0
(-5502 2175);
DISPLAY 0.872340 (-5502 2175);
PAINT GREEN (-5502 2175);
DISPLAY INVISIBLE (-5502 2175);
FORCEADD TAP..6
(-5500 2225);
FORCEPROP 3 LASTPIN (-5450 2225) SIG_NAME M_D_DQ<14>
J 0
(-5440 2235);
DISPLAY 0.659574 (-5440 2235);
PAINT MONO (-5440 2235);
DISPLAY INVISIBLE (-5440 2235);
FORCEPROP 1 LASTPIN (-5450 2225) BN 14
J 0
(-5502 2233);
DISPLAY 0.617021 (-5502 2233);
PAINT PINK (-5502 2233);
FORCEPROP 2 LAST CDS_LIB mstr_standard
J 0
(-5500 2225);
PAINT MONO (-5500 2225);
DISPLAY INVISIBLE (-5500 2225);
FORCEPROP 1 LAST BODY_TYPE PLUMBING
J 0
(-5500 2175);
DISPLAY 1.595745 (-5500 2175);
PAINT GREEN (-5500 2175);
DISPLAY INVISIBLE (-5500 2175);
FORCEPROP 1 LAST HDL_TAP TRUE
J 0
(-5175 2100);
DISPLAY 1.595745 (-5175 2100);
PAINT GREEN (-5175 2100);
DISPLAY INVISIBLE (-5175 2100);
FORCEPROP 1 LAST PATH I36
J 0
(-5502 2225);
DISPLAY 0.872340 (-5502 2225);
PAINT GREEN (-5502 2225);
DISPLAY INVISIBLE (-5502 2225);
FORCEADD TAP..6
(-5500 2275);
FORCEPROP 3 LASTPIN (-5450 2275) SIG_NAME M_D_DQ<15>
J 0
(-5440 2285);
DISPLAY 0.659574 (-5440 2285);
PAINT MONO (-5440 2285);
DISPLAY INVISIBLE (-5440 2285);
FORCEPROP 1 LASTPIN (-5450 2275) BN 15
J 0
(-5502 2283);
DISPLAY 0.617021 (-5502 2283);
PAINT PINK (-5502 2283);
FORCEPROP 2 LAST CDS_LIB mstr_standard
J 0
(-5500 2275);
PAINT MONO (-5500 2275);
DISPLAY INVISIBLE (-5500 2275);
FORCEPROP 1 LAST BODY_TYPE PLUMBING
J 0
(-5500 2225);
DISPLAY 1.595745 (-5500 2225);
PAINT GREEN (-5500 2225);
DISPLAY INVISIBLE (-5500 2225);
FORCEPROP 1 LAST HDL_TAP TRUE
J 0
(-5175 2150);
DISPLAY 1.595745 (-5175 2150);
PAINT GREEN (-5175 2150);
DISPLAY INVISIBLE (-5175 2150);
FORCEPROP 1 LAST PATH I37
J 0
(-5502 2275);
DISPLAY 0.872340 (-5502 2275);
PAINT GREEN (-5502 2275);
DISPLAY INVISIBLE (-5502 2275);
FORCEADD TAP..6
(-5500 2325);
FORCEPROP 3 LASTPIN (-5450 2325) SIG_NAME M_D_DQ<16>
J 0
(-5440 2335);
DISPLAY 0.659574 (-5440 2335);
PAINT MONO (-5440 2335);
DISPLAY INVISIBLE (-5440 2335);
FORCEPROP 1 LASTPIN (-5450 2325) BN 16
J 0
(-5502 2333);
DISPLAY 0.617021 (-5502 2333);
PAINT PINK (-5502 2333);
FORCEPROP 2 LAST CDS_LIB mstr_standard
J 0
(-5500 2325);
PAINT MONO (-5500 2325);
DISPLAY INVISIBLE (-5500 2325);
FORCEPROP 1 LAST BODY_TYPE PLUMBING
J 0
(-5500 2275);
DISPLAY 1.595745 (-5500 2275);
PAINT GREEN (-5500 2275);
DISPLAY INVISIBLE (-5500 2275);
FORCEPROP 1 LAST HDL_TAP TRUE
J 0
(-5175 2200);
DISPLAY 1.595745 (-5175 2200);
PAINT GREEN (-5175 2200);
DISPLAY INVISIBLE (-5175 2200);
FORCEPROP 1 LAST PATH I38
J 0
(-5502 2325);
DISPLAY 0.872340 (-5502 2325);
PAINT GREEN (-5502 2325);
DISPLAY INVISIBLE (-5502 2325);
FORCEADD TAP..6
(-5500 2375);
FORCEPROP 3 LASTPIN (-5450 2375) SIG_NAME M_D_DQ<17>
J 0
(-5440 2385);
DISPLAY 0.659574 (-5440 2385);
PAINT MONO (-5440 2385);
DISPLAY INVISIBLE (-5440 2385);
FORCEPROP 1 LASTPIN (-5450 2375) BN 17
J 0
(-5502 2383);
DISPLAY 0.617021 (-5502 2383);
PAINT PINK (-5502 2383);
FORCEPROP 2 LAST CDS_LIB mstr_standard
J 0
(-5500 2375);
PAINT MONO (-5500 2375);
DISPLAY INVISIBLE (-5500 2375);
FORCEPROP 1 LAST BODY_TYPE PLUMBING
J 0
(-5500 2325);
DISPLAY 1.595745 (-5500 2325);
PAINT GREEN (-5500 2325);
DISPLAY INVISIBLE (-5500 2325);
FORCEPROP 1 LAST HDL_TAP TRUE
J 0
(-5175 2250);
DISPLAY 1.595745 (-5175 2250);
PAINT GREEN (-5175 2250);
DISPLAY INVISIBLE (-5175 2250);
FORCEPROP 1 LAST PATH I39
J 0
(-5502 2375);
DISPLAY 0.872340 (-5502 2375);
PAINT GREEN (-5502 2375);
DISPLAY INVISIBLE (-5502 2375);
FORCEADD OFFPAGE..6
(-6350 1475);
FORCEPROP 2 LAST $XR1 50 
J 0
(-6719 1475);
DISPLAY 0.638298 (-6719 1475);
PAINT MONO (-6719 1475);
FORCEPROP 2 LAST $XR0 49 
J 0
(-6629 1475);
DISPLAY 0.638298 (-6629 1475);
PAINT MONO (-6629 1475);
FORCEPROP 2 LAST CDS_LIB mstr_standard
J 0
(-6350 1475);
PAINT MONO (-6350 1475);
DISPLAY INVISIBLE (-6350 1475);
FORCEPROP 1 LAST OFFPAGE TRUE
J 0
(-6025 1350);
DISPLAY 1.170213 (-6025 1350);
PAINT GREEN (-6025 1350);
DISPLAY INVISIBLE (-6025 1350);
FORCEPROP 1 LAST COMMENT_BODY TRUE
J 0
(-6250 1400);
DISPLAY 1.170213 (-6250 1400);
PAINT GREEN (-6250 1400);
DISPLAY INVISIBLE (-6250 1400);
FORCEPROP 2 LAST PATH I4
J 0
(-6300 1550);
DISPLAY 1.021277 (-6300 1550);
PAINT ORANGE (-6300 1550);
DISPLAY INVISIBLE (-6300 1550);
FORCEADD TAP..6
(-5500 2425);
FORCEPROP 3 LASTPIN (-5450 2425) SIG_NAME M_D_DQ<18>
J 0
(-5440 2435);
DISPLAY 0.659574 (-5440 2435);
PAINT MONO (-5440 2435);
DISPLAY INVISIBLE (-5440 2435);
FORCEPROP 1 LASTPIN (-5450 2425) BN 18
J 0
(-5502 2433);
DISPLAY 0.617021 (-5502 2433);
PAINT PINK (-5502 2433);
FORCEPROP 2 LAST CDS_LIB mstr_standard
J 0
(-5500 2425);
PAINT MONO (-5500 2425);
DISPLAY INVISIBLE (-5500 2425);
FORCEPROP 1 LAST BODY_TYPE PLUMBING
J 0
(-5500 2375);
DISPLAY 1.595745 (-5500 2375);
PAINT GREEN (-5500 2375);
DISPLAY INVISIBLE (-5500 2375);
FORCEPROP 1 LAST HDL_TAP TRUE
J 0
(-5175 2300);
DISPLAY 1.595745 (-5175 2300);
PAINT GREEN (-5175 2300);
DISPLAY INVISIBLE (-5175 2300);
FORCEPROP 1 LAST PATH I40
J 0
(-5502 2425);
DISPLAY 0.872340 (-5502 2425);
PAINT GREEN (-5502 2425);
DISPLAY INVISIBLE (-5502 2425);
FORCEADD TAP..6
(-5500 2475);
FORCEPROP 3 LASTPIN (-5450 2475) SIG_NAME M_D_DQ<19>
J 0
(-5440 2485);
DISPLAY 0.659574 (-5440 2485);
PAINT MONO (-5440 2485);
DISPLAY INVISIBLE (-5440 2485);
FORCEPROP 1 LASTPIN (-5450 2475) BN 19
J 0
(-5502 2483);
DISPLAY 0.617021 (-5502 2483);
PAINT PINK (-5502 2483);
FORCEPROP 2 LAST CDS_LIB mstr_standard
J 0
(-5500 2475);
PAINT MONO (-5500 2475);
DISPLAY INVISIBLE (-5500 2475);
FORCEPROP 1 LAST BODY_TYPE PLUMBING
J 0
(-5500 2425);
DISPLAY 1.595745 (-5500 2425);
PAINT GREEN (-5500 2425);
DISPLAY INVISIBLE (-5500 2425);
FORCEPROP 1 LAST HDL_TAP TRUE
J 0
(-5175 2350);
DISPLAY 1.595745 (-5175 2350);
PAINT GREEN (-5175 2350);
DISPLAY INVISIBLE (-5175 2350);
FORCEPROP 1 LAST PATH I41
J 0
(-5502 2475);
DISPLAY 0.872340 (-5502 2475);
PAINT GREEN (-5502 2475);
DISPLAY INVISIBLE (-5502 2475);
FORCEADD TAP..6
(-5500 2525);
FORCEPROP 3 LASTPIN (-5450 2525) SIG_NAME M_D_DQ<20>
J 0
(-5440 2535);
DISPLAY 0.659574 (-5440 2535);
PAINT MONO (-5440 2535);
DISPLAY INVISIBLE (-5440 2535);
FORCEPROP 1 LASTPIN (-5450 2525) BN 20
J 0
(-5502 2533);
DISPLAY 0.617021 (-5502 2533);
PAINT PINK (-5502 2533);
FORCEPROP 2 LAST CDS_LIB mstr_standard
J 0
(-5500 2525);
PAINT MONO (-5500 2525);
DISPLAY INVISIBLE (-5500 2525);
FORCEPROP 1 LAST BODY_TYPE PLUMBING
J 0
(-5500 2475);
DISPLAY 1.595745 (-5500 2475);
PAINT GREEN (-5500 2475);
DISPLAY INVISIBLE (-5500 2475);
FORCEPROP 1 LAST HDL_TAP TRUE
J 0
(-5175 2400);
DISPLAY 1.595745 (-5175 2400);
PAINT GREEN (-5175 2400);
DISPLAY INVISIBLE (-5175 2400);
FORCEPROP 1 LAST PATH I42
J 0
(-5502 2525);
DISPLAY 0.872340 (-5502 2525);
PAINT GREEN (-5502 2525);
DISPLAY INVISIBLE (-5502 2525);
FORCEADD TAP..6
(-5500 2575);
FORCEPROP 3 LASTPIN (-5450 2575) SIG_NAME M_D_DQ<21>
J 0
(-5440 2585);
DISPLAY 0.659574 (-5440 2585);
PAINT MONO (-5440 2585);
DISPLAY INVISIBLE (-5440 2585);
FORCEPROP 1 LASTPIN (-5450 2575) BN 21
J 0
(-5502 2583);
DISPLAY 0.617021 (-5502 2583);
PAINT PINK (-5502 2583);
FORCEPROP 2 LAST CDS_LIB mstr_standard
J 0
(-5500 2575);
PAINT MONO (-5500 2575);
DISPLAY INVISIBLE (-5500 2575);
FORCEPROP 1 LAST BODY_TYPE PLUMBING
J 0
(-5500 2525);
DISPLAY 1.595745 (-5500 2525);
PAINT GREEN (-5500 2525);
DISPLAY INVISIBLE (-5500 2525);
FORCEPROP 1 LAST HDL_TAP TRUE
J 0
(-5175 2450);
DISPLAY 1.595745 (-5175 2450);
PAINT GREEN (-5175 2450);
DISPLAY INVISIBLE (-5175 2450);
FORCEPROP 1 LAST PATH I43
J 0
(-5502 2575);
DISPLAY 0.872340 (-5502 2575);
PAINT GREEN (-5502 2575);
DISPLAY INVISIBLE (-5502 2575);
FORCEADD TAP..6
(-5500 2625);
FORCEPROP 3 LASTPIN (-5450 2625) SIG_NAME M_D_DQ<22>
J 0
(-5440 2635);
DISPLAY 0.659574 (-5440 2635);
PAINT MONO (-5440 2635);
DISPLAY INVISIBLE (-5440 2635);
FORCEPROP 1 LASTPIN (-5450 2625) BN 22
J 0
(-5502 2633);
DISPLAY 0.617021 (-5502 2633);
PAINT PINK (-5502 2633);
FORCEPROP 2 LAST CDS_LIB mstr_standard
J 0
(-5500 2625);
PAINT MONO (-5500 2625);
DISPLAY INVISIBLE (-5500 2625);
FORCEPROP 1 LAST BODY_TYPE PLUMBING
J 0
(-5500 2575);
DISPLAY 1.595745 (-5500 2575);
PAINT GREEN (-5500 2575);
DISPLAY INVISIBLE (-5500 2575);
FORCEPROP 1 LAST HDL_TAP TRUE
J 0
(-5175 2500);
DISPLAY 1.595745 (-5175 2500);
PAINT GREEN (-5175 2500);
DISPLAY INVISIBLE (-5175 2500);
FORCEPROP 1 LAST PATH I44
J 0
(-5502 2625);
DISPLAY 0.872340 (-5502 2625);
PAINT GREEN (-5502 2625);
DISPLAY INVISIBLE (-5502 2625);
FORCEADD TAP..6
(-5500 2675);
FORCEPROP 3 LASTPIN (-5450 2675) SIG_NAME M_D_DQ<23>
J 0
(-5440 2685);
DISPLAY 0.659574 (-5440 2685);
PAINT MONO (-5440 2685);
DISPLAY INVISIBLE (-5440 2685);
FORCEPROP 1 LASTPIN (-5450 2675) BN 23
J 0
(-5502 2683);
DISPLAY 0.617021 (-5502 2683);
PAINT PINK (-5502 2683);
FORCEPROP 2 LAST CDS_LIB mstr_standard
J 0
(-5500 2675);
PAINT MONO (-5500 2675);
DISPLAY INVISIBLE (-5500 2675);
FORCEPROP 1 LAST BODY_TYPE PLUMBING
J 0
(-5500 2625);
DISPLAY 1.595745 (-5500 2625);
PAINT GREEN (-5500 2625);
DISPLAY INVISIBLE (-5500 2625);
FORCEPROP 1 LAST HDL_TAP TRUE
J 0
(-5175 2550);
DISPLAY 1.595745 (-5175 2550);
PAINT GREEN (-5175 2550);
DISPLAY INVISIBLE (-5175 2550);
FORCEPROP 1 LAST PATH I45
J 0
(-5502 2675);
DISPLAY 0.872340 (-5502 2675);
PAINT GREEN (-5502 2675);
DISPLAY INVISIBLE (-5502 2675);
FORCEADD TAP..6
(-5500 2725);
FORCEPROP 3 LASTPIN (-5450 2725) SIG_NAME M_D_DQ<24>
J 0
(-5440 2735);
DISPLAY 0.659574 (-5440 2735);
PAINT MONO (-5440 2735);
DISPLAY INVISIBLE (-5440 2735);
FORCEPROP 1 LASTPIN (-5450 2725) BN 24
J 0
(-5502 2733);
DISPLAY 0.617021 (-5502 2733);
PAINT PINK (-5502 2733);
FORCEPROP 2 LAST CDS_LIB mstr_standard
J 0
(-5500 2725);
PAINT MONO (-5500 2725);
DISPLAY INVISIBLE (-5500 2725);
FORCEPROP 1 LAST BODY_TYPE PLUMBING
J 0
(-5500 2675);
DISPLAY 1.595745 (-5500 2675);
PAINT GREEN (-5500 2675);
DISPLAY INVISIBLE (-5500 2675);
FORCEPROP 1 LAST HDL_TAP TRUE
J 0
(-5175 2600);
DISPLAY 1.595745 (-5175 2600);
PAINT GREEN (-5175 2600);
DISPLAY INVISIBLE (-5175 2600);
FORCEPROP 1 LAST PATH I46
J 0
(-5502 2725);
DISPLAY 0.872340 (-5502 2725);
PAINT GREEN (-5502 2725);
DISPLAY INVISIBLE (-5502 2725);
FORCEADD TAP..6
(-5500 2825);
FORCEPROP 3 LASTPIN (-5450 2825) SIG_NAME M_D_DQ<26>
J 0
(-5440 2835);
DISPLAY 0.659574 (-5440 2835);
PAINT MONO (-5440 2835);
DISPLAY INVISIBLE (-5440 2835);
FORCEPROP 1 LASTPIN (-5450 2825) BN 26
J 0
(-5502 2833);
DISPLAY 0.617021 (-5502 2833);
PAINT PINK (-5502 2833);
FORCEPROP 2 LAST CDS_LIB mstr_standard
J 0
(-5500 2825);
PAINT MONO (-5500 2825);
DISPLAY INVISIBLE (-5500 2825);
FORCEPROP 1 LAST BODY_TYPE PLUMBING
J 0
(-5500 2775);
DISPLAY 1.595745 (-5500 2775);
PAINT GREEN (-5500 2775);
DISPLAY INVISIBLE (-5500 2775);
FORCEPROP 1 LAST HDL_TAP TRUE
J 0
(-5175 2700);
DISPLAY 1.595745 (-5175 2700);
PAINT GREEN (-5175 2700);
DISPLAY INVISIBLE (-5175 2700);
FORCEPROP 1 LAST PATH I47
J 0
(-5502 2825);
DISPLAY 0.872340 (-5502 2825);
PAINT GREEN (-5502 2825);
DISPLAY INVISIBLE (-5502 2825);
FORCEADD TAP..6
(-5500 2775);
FORCEPROP 3 LASTPIN (-5450 2775) SIG_NAME M_D_DQ<25>
J 0
(-5440 2785);
DISPLAY 0.659574 (-5440 2785);
PAINT MONO (-5440 2785);
DISPLAY INVISIBLE (-5440 2785);
FORCEPROP 1 LASTPIN (-5450 2775) BN 25
J 0
(-5502 2783);
DISPLAY 0.617021 (-5502 2783);
PAINT PINK (-5502 2783);
FORCEPROP 2 LAST CDS_LIB mstr_standard
J 0
(-5500 2775);
PAINT MONO (-5500 2775);
DISPLAY INVISIBLE (-5500 2775);
FORCEPROP 1 LAST BODY_TYPE PLUMBING
J 0
(-5500 2725);
DISPLAY 1.595745 (-5500 2725);
PAINT GREEN (-5500 2725);
DISPLAY INVISIBLE (-5500 2725);
FORCEPROP 1 LAST HDL_TAP TRUE
J 0
(-5175 2650);
DISPLAY 1.595745 (-5175 2650);
PAINT GREEN (-5175 2650);
DISPLAY INVISIBLE (-5175 2650);
FORCEPROP 1 LAST PATH I48
J 0
(-5502 2775);
DISPLAY 0.872340 (-5502 2775);
PAINT GREEN (-5502 2775);
DISPLAY INVISIBLE (-5502 2775);
FORCEADD TAP..6
(-5500 2875);
FORCEPROP 3 LASTPIN (-5450 2875) SIG_NAME M_D_DQ<27>
J 0
(-5440 2885);
DISPLAY 0.659574 (-5440 2885);
PAINT MONO (-5440 2885);
DISPLAY INVISIBLE (-5440 2885);
FORCEPROP 1 LASTPIN (-5450 2875) BN 27
J 0
(-5502 2883);
DISPLAY 0.617021 (-5502 2883);
PAINT PINK (-5502 2883);
FORCEPROP 2 LAST CDS_LIB mstr_standard
J 0
(-5500 2875);
PAINT MONO (-5500 2875);
DISPLAY INVISIBLE (-5500 2875);
FORCEPROP 1 LAST BODY_TYPE PLUMBING
J 0
(-5500 2825);
DISPLAY 1.595745 (-5500 2825);
PAINT GREEN (-5500 2825);
DISPLAY INVISIBLE (-5500 2825);
FORCEPROP 1 LAST HDL_TAP TRUE
J 0
(-5175 2750);
DISPLAY 1.595745 (-5175 2750);
PAINT GREEN (-5175 2750);
DISPLAY INVISIBLE (-5175 2750);
FORCEPROP 1 LAST PATH I49
J 0
(-5502 2875);
DISPLAY 0.872340 (-5502 2875);
PAINT GREEN (-5502 2875);
DISPLAY INVISIBLE (-5502 2875);
FORCEADD TAP..6
(-5500 625);
FORCEPROP 3 LASTPIN (-5450 625) SIG_NAME M_D_CLK_DN<0>
J 0
(-5440 635);
DISPLAY 0.659574 (-5440 635);
PAINT MONO (-5440 635);
DISPLAY INVISIBLE (-5440 635);
FORCEPROP 1 LASTPIN (-5450 625) BN 0
J 0
(-5502 633);
DISPLAY 0.617021 (-5502 633);
PAINT PINK (-5502 633);
FORCEPROP 2 LAST CDS_LIB mstr_standard
J 0
(-5500 625);
PAINT MONO (-5500 625);
DISPLAY INVISIBLE (-5500 625);
FORCEPROP 1 LAST BODY_TYPE PLUMBING
J 0
(-5500 575);
DISPLAY 1.595745 (-5500 575);
PAINT GREEN (-5500 575);
DISPLAY INVISIBLE (-5500 575);
FORCEPROP 1 LAST HDL_TAP TRUE
J 0
(-5175 500);
DISPLAY 1.595745 (-5175 500);
PAINT GREEN (-5175 500);
DISPLAY INVISIBLE (-5175 500);
FORCEPROP 1 LAST PATH I5
J 0
(-5502 625);
DISPLAY 0.872340 (-5502 625);
PAINT GREEN (-5502 625);
DISPLAY INVISIBLE (-5502 625);
FORCEADD TAP..6
(-5500 2925);
FORCEPROP 3 LASTPIN (-5450 2925) SIG_NAME M_D_DQ<28>
J 0
(-5440 2935);
DISPLAY 0.659574 (-5440 2935);
PAINT MONO (-5440 2935);
DISPLAY INVISIBLE (-5440 2935);
FORCEPROP 1 LASTPIN (-5450 2925) BN 28
J 0
(-5502 2933);
DISPLAY 0.617021 (-5502 2933);
PAINT PINK (-5502 2933);
FORCEPROP 2 LAST CDS_LIB mstr_standard
J 0
(-5500 2925);
PAINT MONO (-5500 2925);
DISPLAY INVISIBLE (-5500 2925);
FORCEPROP 1 LAST BODY_TYPE PLUMBING
J 0
(-5500 2875);
DISPLAY 1.595745 (-5500 2875);
PAINT GREEN (-5500 2875);
DISPLAY INVISIBLE (-5500 2875);
FORCEPROP 1 LAST HDL_TAP TRUE
J 0
(-5175 2800);
DISPLAY 1.595745 (-5175 2800);
PAINT GREEN (-5175 2800);
DISPLAY INVISIBLE (-5175 2800);
FORCEPROP 1 LAST PATH I50
J 0
(-5502 2925);
DISPLAY 0.872340 (-5502 2925);
PAINT GREEN (-5502 2925);
DISPLAY INVISIBLE (-5502 2925);
FORCEADD TAP..6
(-5500 2975);
FORCEPROP 3 LASTPIN (-5450 2975) SIG_NAME M_D_DQ<29>
J 0
(-5440 2985);
DISPLAY 0.659574 (-5440 2985);
PAINT MONO (-5440 2985);
DISPLAY INVISIBLE (-5440 2985);
FORCEPROP 1 LASTPIN (-5450 2975) BN 29
J 0
(-5502 2983);
DISPLAY 0.617021 (-5502 2983);
PAINT PINK (-5502 2983);
FORCEPROP 2 LAST CDS_LIB mstr_standard
J 0
(-5500 2975);
PAINT MONO (-5500 2975);
DISPLAY INVISIBLE (-5500 2975);
FORCEPROP 1 LAST BODY_TYPE PLUMBING
J 0
(-5500 2925);
DISPLAY 1.595745 (-5500 2925);
PAINT GREEN (-5500 2925);
DISPLAY INVISIBLE (-5500 2925);
FORCEPROP 1 LAST HDL_TAP TRUE
J 0
(-5175 2850);
DISPLAY 1.595745 (-5175 2850);
PAINT GREEN (-5175 2850);
DISPLAY INVISIBLE (-5175 2850);
FORCEPROP 1 LAST PATH I51
J 0
(-5502 2975);
DISPLAY 0.872340 (-5502 2975);
PAINT GREEN (-5502 2975);
DISPLAY INVISIBLE (-5502 2975);
FORCEADD TAP..6
(-5500 3075);
FORCEPROP 3 LASTPIN (-5450 3075) SIG_NAME M_D_DQ<31>
J 0
(-5440 3085);
DISPLAY 0.659574 (-5440 3085);
PAINT MONO (-5440 3085);
DISPLAY INVISIBLE (-5440 3085);
FORCEPROP 1 LASTPIN (-5450 3075) BN 31
J 0
(-5502 3083);
DISPLAY 0.617021 (-5502 3083);
PAINT PINK (-5502 3083);
FORCEPROP 2 LAST CDS_LIB mstr_standard
J 0
(-5500 3075);
PAINT MONO (-5500 3075);
DISPLAY INVISIBLE (-5500 3075);
FORCEPROP 1 LAST BODY_TYPE PLUMBING
J 0
(-5500 3025);
DISPLAY 1.595745 (-5500 3025);
PAINT GREEN (-5500 3025);
DISPLAY INVISIBLE (-5500 3025);
FORCEPROP 1 LAST HDL_TAP TRUE
J 0
(-5175 2950);
DISPLAY 1.595745 (-5175 2950);
PAINT GREEN (-5175 2950);
DISPLAY INVISIBLE (-5175 2950);
FORCEPROP 1 LAST PATH I52
J 0
(-5502 3075);
DISPLAY 0.872340 (-5502 3075);
PAINT GREEN (-5502 3075);
DISPLAY INVISIBLE (-5502 3075);
FORCEADD TAP..6
(-5500 3025);
FORCEPROP 3 LASTPIN (-5450 3025) SIG_NAME M_D_DQ<30>
J 0
(-5440 3035);
DISPLAY 0.659574 (-5440 3035);
PAINT MONO (-5440 3035);
DISPLAY INVISIBLE (-5440 3035);
FORCEPROP 1 LASTPIN (-5450 3025) BN 30
J 0
(-5502 3033);
DISPLAY 0.617021 (-5502 3033);
PAINT PINK (-5502 3033);
FORCEPROP 2 LAST CDS_LIB mstr_standard
J 0
(-5500 3025);
PAINT MONO (-5500 3025);
DISPLAY INVISIBLE (-5500 3025);
FORCEPROP 1 LAST BODY_TYPE PLUMBING
J 0
(-5500 2975);
DISPLAY 1.595745 (-5500 2975);
PAINT GREEN (-5500 2975);
DISPLAY INVISIBLE (-5500 2975);
FORCEPROP 1 LAST HDL_TAP TRUE
J 0
(-5175 2900);
DISPLAY 1.595745 (-5175 2900);
PAINT GREEN (-5175 2900);
DISPLAY INVISIBLE (-5175 2900);
FORCEPROP 1 LAST PATH I53
J 0
(-5502 3025);
DISPLAY 0.872340 (-5502 3025);
PAINT GREEN (-5502 3025);
DISPLAY INVISIBLE (-5502 3025);
FORCEADD TAP..6
(-5500 3125);
FORCEPROP 3 LASTPIN (-5450 3125) SIG_NAME M_D_DQ<32>
J 0
(-5440 3135);
DISPLAY 0.659574 (-5440 3135);
PAINT MONO (-5440 3135);
DISPLAY INVISIBLE (-5440 3135);
FORCEPROP 1 LASTPIN (-5450 3125) BN 32
J 0
(-5502 3133);
DISPLAY 0.617021 (-5502 3133);
PAINT PINK (-5502 3133);
FORCEPROP 2 LAST CDS_LIB mstr_standard
J 0
(-5500 3125);
PAINT MONO (-5500 3125);
DISPLAY INVISIBLE (-5500 3125);
FORCEPROP 1 LAST BODY_TYPE PLUMBING
J 0
(-5500 3075);
DISPLAY 1.595745 (-5500 3075);
PAINT GREEN (-5500 3075);
DISPLAY INVISIBLE (-5500 3075);
FORCEPROP 1 LAST HDL_TAP TRUE
J 0
(-5175 3000);
DISPLAY 1.595745 (-5175 3000);
PAINT GREEN (-5175 3000);
DISPLAY INVISIBLE (-5175 3000);
FORCEPROP 1 LAST PATH I54
J 0
(-5502 3125);
DISPLAY 0.872340 (-5502 3125);
PAINT GREEN (-5502 3125);
DISPLAY INVISIBLE (-5502 3125);
FORCEADD TAP..6
(-5500 3175);
FORCEPROP 3 LASTPIN (-5450 3175) SIG_NAME M_D_DQ<33>
J 0
(-5440 3185);
DISPLAY 0.659574 (-5440 3185);
PAINT MONO (-5440 3185);
DISPLAY INVISIBLE (-5440 3185);
FORCEPROP 1 LASTPIN (-5450 3175) BN 33
J 0
(-5502 3183);
DISPLAY 0.617021 (-5502 3183);
PAINT PINK (-5502 3183);
FORCEPROP 2 LAST CDS_LIB mstr_standard
J 0
(-5500 3175);
PAINT MONO (-5500 3175);
DISPLAY INVISIBLE (-5500 3175);
FORCEPROP 1 LAST BODY_TYPE PLUMBING
J 0
(-5500 3125);
DISPLAY 1.595745 (-5500 3125);
PAINT GREEN (-5500 3125);
DISPLAY INVISIBLE (-5500 3125);
FORCEPROP 1 LAST HDL_TAP TRUE
J 0
(-5175 3050);
DISPLAY 1.595745 (-5175 3050);
PAINT GREEN (-5175 3050);
DISPLAY INVISIBLE (-5175 3050);
FORCEPROP 1 LAST PATH I55
J 0
(-5502 3175);
DISPLAY 0.872340 (-5502 3175);
PAINT GREEN (-5502 3175);
DISPLAY INVISIBLE (-5502 3175);
FORCEADD TAP..6
(-5500 3225);
FORCEPROP 3 LASTPIN (-5450 3225) SIG_NAME M_D_DQ<34>
J 0
(-5440 3235);
DISPLAY 0.659574 (-5440 3235);
PAINT MONO (-5440 3235);
DISPLAY INVISIBLE (-5440 3235);
FORCEPROP 1 LASTPIN (-5450 3225) BN 34
J 0
(-5502 3233);
DISPLAY 0.617021 (-5502 3233);
PAINT PINK (-5502 3233);
FORCEPROP 2 LAST CDS_LIB mstr_standard
J 0
(-5500 3225);
PAINT MONO (-5500 3225);
DISPLAY INVISIBLE (-5500 3225);
FORCEPROP 1 LAST BODY_TYPE PLUMBING
J 0
(-5500 3175);
DISPLAY 1.595745 (-5500 3175);
PAINT GREEN (-5500 3175);
DISPLAY INVISIBLE (-5500 3175);
FORCEPROP 1 LAST HDL_TAP TRUE
J 0
(-5175 3100);
DISPLAY 1.595745 (-5175 3100);
PAINT GREEN (-5175 3100);
DISPLAY INVISIBLE (-5175 3100);
FORCEPROP 1 LAST PATH I56
J 0
(-5502 3225);
DISPLAY 0.872340 (-5502 3225);
PAINT GREEN (-5502 3225);
DISPLAY INVISIBLE (-5502 3225);
FORCEADD TAP..6
(-5500 3325);
FORCEPROP 3 LASTPIN (-5450 3325) SIG_NAME M_D_DQ<36>
J 0
(-5440 3335);
DISPLAY 0.659574 (-5440 3335);
PAINT MONO (-5440 3335);
DISPLAY INVISIBLE (-5440 3335);
FORCEPROP 1 LASTPIN (-5450 3325) BN 36
J 0
(-5502 3333);
DISPLAY 0.617021 (-5502 3333);
PAINT PINK (-5502 3333);
FORCEPROP 2 LAST CDS_LIB mstr_standard
J 0
(-5500 3325);
PAINT MONO (-5500 3325);
DISPLAY INVISIBLE (-5500 3325);
FORCEPROP 1 LAST BODY_TYPE PLUMBING
J 0
(-5500 3275);
DISPLAY 1.595745 (-5500 3275);
PAINT GREEN (-5500 3275);
DISPLAY INVISIBLE (-5500 3275);
FORCEPROP 1 LAST HDL_TAP TRUE
J 0
(-5175 3200);
DISPLAY 1.595745 (-5175 3200);
PAINT GREEN (-5175 3200);
DISPLAY INVISIBLE (-5175 3200);
FORCEPROP 1 LAST PATH I57
J 0
(-5502 3325);
DISPLAY 0.872340 (-5502 3325);
PAINT GREEN (-5502 3325);
DISPLAY INVISIBLE (-5502 3325);
FORCEADD TAP..6
(-5500 3275);
FORCEPROP 3 LASTPIN (-5450 3275) SIG_NAME M_D_DQ<35>
J 0
(-5440 3285);
DISPLAY 0.659574 (-5440 3285);
PAINT MONO (-5440 3285);
DISPLAY INVISIBLE (-5440 3285);
FORCEPROP 1 LASTPIN (-5450 3275) BN 35
J 0
(-5502 3283);
DISPLAY 0.617021 (-5502 3283);
PAINT PINK (-5502 3283);
FORCEPROP 2 LAST CDS_LIB mstr_standard
J 0
(-5500 3275);
PAINT MONO (-5500 3275);
DISPLAY INVISIBLE (-5500 3275);
FORCEPROP 1 LAST BODY_TYPE PLUMBING
J 0
(-5500 3225);
DISPLAY 1.595745 (-5500 3225);
PAINT GREEN (-5500 3225);
DISPLAY INVISIBLE (-5500 3225);
FORCEPROP 1 LAST HDL_TAP TRUE
J 0
(-5175 3150);
DISPLAY 1.595745 (-5175 3150);
PAINT GREEN (-5175 3150);
DISPLAY INVISIBLE (-5175 3150);
FORCEPROP 1 LAST PATH I58
J 0
(-5502 3275);
DISPLAY 0.872340 (-5502 3275);
PAINT GREEN (-5502 3275);
DISPLAY INVISIBLE (-5502 3275);
FORCEADD TAP..6
(-5500 3375);
FORCEPROP 3 LASTPIN (-5450 3375) SIG_NAME M_D_DQ<37>
J 0
(-5440 3385);
DISPLAY 0.659574 (-5440 3385);
PAINT MONO (-5440 3385);
DISPLAY INVISIBLE (-5440 3385);
FORCEPROP 1 LASTPIN (-5450 3375) BN 37
J 0
(-5502 3383);
DISPLAY 0.617021 (-5502 3383);
PAINT PINK (-5502 3383);
FORCEPROP 2 LAST CDS_LIB mstr_standard
J 0
(-5500 3375);
PAINT MONO (-5500 3375);
DISPLAY INVISIBLE (-5500 3375);
FORCEPROP 1 LAST BODY_TYPE PLUMBING
J 0
(-5500 3325);
DISPLAY 1.595745 (-5500 3325);
PAINT GREEN (-5500 3325);
DISPLAY INVISIBLE (-5500 3325);
FORCEPROP 1 LAST HDL_TAP TRUE
J 0
(-5175 3250);
DISPLAY 1.595745 (-5175 3250);
PAINT GREEN (-5175 3250);
DISPLAY INVISIBLE (-5175 3250);
FORCEPROP 1 LAST PATH I59
J 0
(-5502 3375);
DISPLAY 0.872340 (-5502 3375);
PAINT GREEN (-5502 3375);
DISPLAY INVISIBLE (-5502 3375);
FORCEADD TAP..6
(-5500 675);
FORCEPROP 3 LASTPIN (-5450 675) SIG_NAME M_D_CLK_DN<1>
J 0
(-5440 685);
DISPLAY 0.659574 (-5440 685);
PAINT MONO (-5440 685);
DISPLAY INVISIBLE (-5440 685);
FORCEPROP 1 LASTPIN (-5450 675) BN 1
J 0
(-5502 683);
DISPLAY 0.617021 (-5502 683);
PAINT PINK (-5502 683);
FORCEPROP 2 LAST CDS_LIB mstr_standard
J 0
(-5500 675);
PAINT MONO (-5500 675);
DISPLAY INVISIBLE (-5500 675);
FORCEPROP 1 LAST BODY_TYPE PLUMBING
J 0
(-5500 625);
DISPLAY 1.595745 (-5500 625);
PAINT GREEN (-5500 625);
DISPLAY INVISIBLE (-5500 625);
FORCEPROP 1 LAST HDL_TAP TRUE
J 0
(-5175 550);
DISPLAY 1.595745 (-5175 550);
PAINT GREEN (-5175 550);
DISPLAY INVISIBLE (-5175 550);
FORCEPROP 1 LAST PATH I6
J 0
(-5502 675);
DISPLAY 0.872340 (-5502 675);
PAINT GREEN (-5502 675);
DISPLAY INVISIBLE (-5502 675);
FORCEADD TAP..6
(-5500 3425);
FORCEPROP 3 LASTPIN (-5450 3425) SIG_NAME M_D_DQ<38>
J 0
(-5440 3435);
DISPLAY 0.659574 (-5440 3435);
PAINT MONO (-5440 3435);
DISPLAY INVISIBLE (-5440 3435);
FORCEPROP 1 LASTPIN (-5450 3425) BN 38
J 0
(-5502 3433);
DISPLAY 0.617021 (-5502 3433);
PAINT PINK (-5502 3433);
FORCEPROP 2 LAST CDS_LIB mstr_standard
J 0
(-5500 3425);
PAINT MONO (-5500 3425);
DISPLAY INVISIBLE (-5500 3425);
FORCEPROP 1 LAST BODY_TYPE PLUMBING
J 0
(-5500 3375);
DISPLAY 1.595745 (-5500 3375);
PAINT GREEN (-5500 3375);
DISPLAY INVISIBLE (-5500 3375);
FORCEPROP 1 LAST HDL_TAP TRUE
J 0
(-5175 3300);
DISPLAY 1.595745 (-5175 3300);
PAINT GREEN (-5175 3300);
DISPLAY INVISIBLE (-5175 3300);
FORCEPROP 1 LAST PATH I60
J 0
(-5502 3425);
DISPLAY 0.872340 (-5502 3425);
PAINT GREEN (-5502 3425);
DISPLAY INVISIBLE (-5502 3425);
FORCEADD TAP..6
(-5500 3475);
FORCEPROP 3 LASTPIN (-5450 3475) SIG_NAME M_D_DQ<39>
J 0
(-5440 3485);
DISPLAY 0.659574 (-5440 3485);
PAINT MONO (-5440 3485);
DISPLAY INVISIBLE (-5440 3485);
FORCEPROP 1 LASTPIN (-5450 3475) BN 39
J 0
(-5502 3483);
DISPLAY 0.617021 (-5502 3483);
PAINT PINK (-5502 3483);
FORCEPROP 2 LAST CDS_LIB mstr_standard
J 0
(-5500 3475);
PAINT MONO (-5500 3475);
DISPLAY INVISIBLE (-5500 3475);
FORCEPROP 1 LAST BODY_TYPE PLUMBING
J 0
(-5500 3425);
DISPLAY 1.595745 (-5500 3425);
PAINT GREEN (-5500 3425);
DISPLAY INVISIBLE (-5500 3425);
FORCEPROP 1 LAST HDL_TAP TRUE
J 0
(-5175 3350);
DISPLAY 1.595745 (-5175 3350);
PAINT GREEN (-5175 3350);
DISPLAY INVISIBLE (-5175 3350);
FORCEPROP 1 LAST PATH I61
J 0
(-5502 3475);
DISPLAY 0.872340 (-5502 3475);
PAINT GREEN (-5502 3475);
DISPLAY INVISIBLE (-5502 3475);
FORCEADD TAP..6
(-5500 3525);
FORCEPROP 3 LASTPIN (-5450 3525) SIG_NAME M_D_DQ<40>
J 0
(-5440 3535);
DISPLAY 0.659574 (-5440 3535);
PAINT MONO (-5440 3535);
DISPLAY INVISIBLE (-5440 3535);
FORCEPROP 1 LASTPIN (-5450 3525) BN 40
J 0
(-5502 3533);
DISPLAY 0.617021 (-5502 3533);
PAINT PINK (-5502 3533);
FORCEPROP 2 LAST CDS_LIB mstr_standard
J 0
(-5500 3525);
PAINT MONO (-5500 3525);
DISPLAY INVISIBLE (-5500 3525);
FORCEPROP 1 LAST BODY_TYPE PLUMBING
J 0
(-5500 3475);
DISPLAY 1.595745 (-5500 3475);
PAINT GREEN (-5500 3475);
DISPLAY INVISIBLE (-5500 3475);
FORCEPROP 1 LAST HDL_TAP TRUE
J 0
(-5175 3400);
DISPLAY 1.595745 (-5175 3400);
PAINT GREEN (-5175 3400);
DISPLAY INVISIBLE (-5175 3400);
FORCEPROP 1 LAST PATH I62
J 0
(-5502 3525);
DISPLAY 0.872340 (-5502 3525);
PAINT GREEN (-5502 3525);
DISPLAY INVISIBLE (-5502 3525);
FORCEADD TAP..6
(-5500 3575);
FORCEPROP 3 LASTPIN (-5450 3575) SIG_NAME M_D_DQ<41>
J 0
(-5440 3585);
DISPLAY 0.659574 (-5440 3585);
PAINT MONO (-5440 3585);
DISPLAY INVISIBLE (-5440 3585);
FORCEPROP 1 LASTPIN (-5450 3575) BN 41
J 0
(-5502 3583);
DISPLAY 0.617021 (-5502 3583);
PAINT PINK (-5502 3583);
FORCEPROP 2 LAST CDS_LIB mstr_standard
J 0
(-5500 3575);
PAINT MONO (-5500 3575);
DISPLAY INVISIBLE (-5500 3575);
FORCEPROP 1 LAST BODY_TYPE PLUMBING
J 0
(-5500 3525);
DISPLAY 1.595745 (-5500 3525);
PAINT GREEN (-5500 3525);
DISPLAY INVISIBLE (-5500 3525);
FORCEPROP 1 LAST HDL_TAP TRUE
J 0
(-5175 3450);
DISPLAY 1.595745 (-5175 3450);
PAINT GREEN (-5175 3450);
DISPLAY INVISIBLE (-5175 3450);
FORCEPROP 1 LAST PATH I63
J 0
(-5502 3575);
DISPLAY 0.872340 (-5502 3575);
PAINT GREEN (-5502 3575);
DISPLAY INVISIBLE (-5502 3575);
FORCEADD TAP..6
(-5500 3625);
FORCEPROP 3 LASTPIN (-5450 3625) SIG_NAME M_D_DQ<42>
J 0
(-5440 3635);
DISPLAY 0.659574 (-5440 3635);
PAINT MONO (-5440 3635);
DISPLAY INVISIBLE (-5440 3635);
FORCEPROP 1 LASTPIN (-5450 3625) BN 42
J 0
(-5502 3633);
DISPLAY 0.617021 (-5502 3633);
PAINT PINK (-5502 3633);
FORCEPROP 2 LAST CDS_LIB mstr_standard
J 0
(-5500 3625);
PAINT MONO (-5500 3625);
DISPLAY INVISIBLE (-5500 3625);
FORCEPROP 1 LAST BODY_TYPE PLUMBING
J 0
(-5500 3575);
DISPLAY 1.595745 (-5500 3575);
PAINT GREEN (-5500 3575);
DISPLAY INVISIBLE (-5500 3575);
FORCEPROP 1 LAST HDL_TAP TRUE
J 0
(-5175 3500);
DISPLAY 1.595745 (-5175 3500);
PAINT GREEN (-5175 3500);
DISPLAY INVISIBLE (-5175 3500);
FORCEPROP 1 LAST PATH I64
J 0
(-5502 3625);
DISPLAY 0.872340 (-5502 3625);
PAINT GREEN (-5502 3625);
DISPLAY INVISIBLE (-5502 3625);
FORCEADD TAP..6
(-5500 3675);
FORCEPROP 3 LASTPIN (-5450 3675) SIG_NAME M_D_DQ<43>
J 0
(-5440 3685);
DISPLAY 0.659574 (-5440 3685);
PAINT MONO (-5440 3685);
DISPLAY INVISIBLE (-5440 3685);
FORCEPROP 1 LASTPIN (-5450 3675) BN 43
J 0
(-5502 3683);
DISPLAY 0.617021 (-5502 3683);
PAINT PINK (-5502 3683);
FORCEPROP 2 LAST CDS_LIB mstr_standard
J 0
(-5500 3675);
PAINT MONO (-5500 3675);
DISPLAY INVISIBLE (-5500 3675);
FORCEPROP 1 LAST BODY_TYPE PLUMBING
J 0
(-5500 3625);
DISPLAY 1.595745 (-5500 3625);
PAINT GREEN (-5500 3625);
DISPLAY INVISIBLE (-5500 3625);
FORCEPROP 1 LAST HDL_TAP TRUE
J 0
(-5175 3550);
DISPLAY 1.595745 (-5175 3550);
PAINT GREEN (-5175 3550);
DISPLAY INVISIBLE (-5175 3550);
FORCEPROP 1 LAST PATH I65
J 0
(-5502 3675);
DISPLAY 0.872340 (-5502 3675);
PAINT GREEN (-5502 3675);
DISPLAY INVISIBLE (-5502 3675);
FORCEADD TAP..6
(-5500 3725);
FORCEPROP 3 LASTPIN (-5450 3725) SIG_NAME M_D_DQ<44>
J 0
(-5440 3735);
DISPLAY 0.659574 (-5440 3735);
PAINT MONO (-5440 3735);
DISPLAY INVISIBLE (-5440 3735);
FORCEPROP 1 LASTPIN (-5450 3725) BN 44
J 0
(-5502 3733);
DISPLAY 0.617021 (-5502 3733);
PAINT PINK (-5502 3733);
FORCEPROP 2 LAST CDS_LIB mstr_standard
J 0
(-5500 3725);
PAINT MONO (-5500 3725);
DISPLAY INVISIBLE (-5500 3725);
FORCEPROP 1 LAST BODY_TYPE PLUMBING
J 0
(-5500 3675);
DISPLAY 1.595745 (-5500 3675);
PAINT GREEN (-5500 3675);
DISPLAY INVISIBLE (-5500 3675);
FORCEPROP 1 LAST HDL_TAP TRUE
J 0
(-5175 3600);
DISPLAY 1.595745 (-5175 3600);
PAINT GREEN (-5175 3600);
DISPLAY INVISIBLE (-5175 3600);
FORCEPROP 1 LAST PATH I66
J 0
(-5502 3725);
DISPLAY 0.872340 (-5502 3725);
PAINT GREEN (-5502 3725);
DISPLAY INVISIBLE (-5502 3725);
FORCEADD TAP..6
(-5500 3775);
FORCEPROP 3 LASTPIN (-5450 3775) SIG_NAME M_D_DQ<45>
J 0
(-5440 3785);
DISPLAY 0.659574 (-5440 3785);
PAINT MONO (-5440 3785);
DISPLAY INVISIBLE (-5440 3785);
FORCEPROP 1 LASTPIN (-5450 3775) BN 45
J 0
(-5502 3783);
DISPLAY 0.617021 (-5502 3783);
PAINT PINK (-5502 3783);
FORCEPROP 2 LAST CDS_LIB mstr_standard
J 0
(-5500 3775);
PAINT MONO (-5500 3775);
DISPLAY INVISIBLE (-5500 3775);
FORCEPROP 1 LAST BODY_TYPE PLUMBING
J 0
(-5500 3725);
DISPLAY 1.595745 (-5500 3725);
PAINT GREEN (-5500 3725);
DISPLAY INVISIBLE (-5500 3725);
FORCEPROP 1 LAST HDL_TAP TRUE
J 0
(-5175 3650);
DISPLAY 1.595745 (-5175 3650);
PAINT GREEN (-5175 3650);
DISPLAY INVISIBLE (-5175 3650);
FORCEPROP 1 LAST PATH I67
J 0
(-5502 3775);
DISPLAY 0.872340 (-5502 3775);
PAINT GREEN (-5502 3775);
DISPLAY INVISIBLE (-5502 3775);
FORCEADD TAP..6
(-5500 3825);
FORCEPROP 3 LASTPIN (-5450 3825) SIG_NAME M_D_DQ<46>
J 0
(-5440 3835);
DISPLAY 0.659574 (-5440 3835);
PAINT MONO (-5440 3835);
DISPLAY INVISIBLE (-5440 3835);
FORCEPROP 1 LASTPIN (-5450 3825) BN 46
J 0
(-5502 3833);
DISPLAY 0.617021 (-5502 3833);
PAINT PINK (-5502 3833);
FORCEPROP 2 LAST CDS_LIB mstr_standard
J 0
(-5500 3825);
PAINT MONO (-5500 3825);
DISPLAY INVISIBLE (-5500 3825);
FORCEPROP 1 LAST BODY_TYPE PLUMBING
J 0
(-5500 3775);
DISPLAY 1.595745 (-5500 3775);
PAINT GREEN (-5500 3775);
DISPLAY INVISIBLE (-5500 3775);
FORCEPROP 1 LAST HDL_TAP TRUE
J 0
(-5175 3700);
DISPLAY 1.595745 (-5175 3700);
PAINT GREEN (-5175 3700);
DISPLAY INVISIBLE (-5175 3700);
FORCEPROP 1 LAST PATH I68
J 0
(-5502 3825);
DISPLAY 0.872340 (-5502 3825);
PAINT GREEN (-5502 3825);
DISPLAY INVISIBLE (-5502 3825);
FORCEADD TAP..6
(-5500 3875);
FORCEPROP 3 LASTPIN (-5450 3875) SIG_NAME M_D_DQ<47>
J 0
(-5440 3885);
DISPLAY 0.659574 (-5440 3885);
PAINT MONO (-5440 3885);
DISPLAY INVISIBLE (-5440 3885);
FORCEPROP 1 LASTPIN (-5450 3875) BN 47
J 0
(-5502 3883);
DISPLAY 0.617021 (-5502 3883);
PAINT PINK (-5502 3883);
FORCEPROP 2 LAST CDS_LIB mstr_standard
J 0
(-5500 3875);
PAINT MONO (-5500 3875);
DISPLAY INVISIBLE (-5500 3875);
FORCEPROP 1 LAST BODY_TYPE PLUMBING
J 0
(-5500 3825);
DISPLAY 1.595745 (-5500 3825);
PAINT GREEN (-5500 3825);
DISPLAY INVISIBLE (-5500 3825);
FORCEPROP 1 LAST HDL_TAP TRUE
J 0
(-5175 3750);
DISPLAY 1.595745 (-5175 3750);
PAINT GREEN (-5175 3750);
DISPLAY INVISIBLE (-5175 3750);
FORCEPROP 1 LAST PATH I69
J 0
(-5502 3875);
DISPLAY 0.872340 (-5502 3875);
PAINT GREEN (-5502 3875);
DISPLAY INVISIBLE (-5502 3875);
FORCEADD TAP..6
(-5500 775);
FORCEPROP 3 LASTPIN (-5450 775) SIG_NAME M_D_CLK_DN<3>
J 0
(-5440 785);
DISPLAY 0.659574 (-5440 785);
PAINT MONO (-5440 785);
DISPLAY INVISIBLE (-5440 785);
FORCEPROP 1 LASTPIN (-5450 775) BN 3
J 0
(-5502 783);
DISPLAY 0.617021 (-5502 783);
PAINT PINK (-5502 783);
FORCEPROP 2 LAST CDS_LIB mstr_standard
J 0
(-5500 775);
PAINT MONO (-5500 775);
DISPLAY INVISIBLE (-5500 775);
FORCEPROP 1 LAST BODY_TYPE PLUMBING
J 0
(-5500 725);
DISPLAY 1.595745 (-5500 725);
PAINT GREEN (-5500 725);
DISPLAY INVISIBLE (-5500 725);
FORCEPROP 1 LAST HDL_TAP TRUE
J 0
(-5175 650);
DISPLAY 1.595745 (-5175 650);
PAINT GREEN (-5175 650);
DISPLAY INVISIBLE (-5175 650);
FORCEPROP 1 LAST PATH I7
J 0
(-5502 775);
DISPLAY 0.872340 (-5502 775);
PAINT GREEN (-5502 775);
DISPLAY INVISIBLE (-5502 775);
FORCEADD TAP..6
(-5500 3925);
FORCEPROP 3 LASTPIN (-5450 3925) SIG_NAME M_D_DQ<48>
J 0
(-5440 3935);
DISPLAY 0.659574 (-5440 3935);
PAINT MONO (-5440 3935);
DISPLAY INVISIBLE (-5440 3935);
FORCEPROP 1 LASTPIN (-5450 3925) BN 48
J 0
(-5502 3933);
DISPLAY 0.617021 (-5502 3933);
PAINT PINK (-5502 3933);
FORCEPROP 2 LAST CDS_LIB mstr_standard
J 0
(-5500 3925);
PAINT MONO (-5500 3925);
DISPLAY INVISIBLE (-5500 3925);
FORCEPROP 1 LAST BODY_TYPE PLUMBING
J 0
(-5500 3875);
DISPLAY 1.595745 (-5500 3875);
PAINT GREEN (-5500 3875);
DISPLAY INVISIBLE (-5500 3875);
FORCEPROP 1 LAST HDL_TAP TRUE
J 0
(-5175 3800);
DISPLAY 1.595745 (-5175 3800);
PAINT GREEN (-5175 3800);
DISPLAY INVISIBLE (-5175 3800);
FORCEPROP 1 LAST PATH I70
J 0
(-5502 3925);
DISPLAY 0.872340 (-5502 3925);
PAINT GREEN (-5502 3925);
DISPLAY INVISIBLE (-5502 3925);
FORCEADD TAP..6
(-5500 3975);
FORCEPROP 3 LASTPIN (-5450 3975) SIG_NAME M_D_DQ<49>
J 0
(-5440 3985);
DISPLAY 0.659574 (-5440 3985);
PAINT MONO (-5440 3985);
DISPLAY INVISIBLE (-5440 3985);
FORCEPROP 1 LASTPIN (-5450 3975) BN 49
J 0
(-5502 3983);
DISPLAY 0.617021 (-5502 3983);
PAINT PINK (-5502 3983);
FORCEPROP 2 LAST CDS_LIB mstr_standard
J 0
(-5500 3975);
PAINT MONO (-5500 3975);
DISPLAY INVISIBLE (-5500 3975);
FORCEPROP 1 LAST BODY_TYPE PLUMBING
J 0
(-5500 3925);
DISPLAY 1.595745 (-5500 3925);
PAINT GREEN (-5500 3925);
DISPLAY INVISIBLE (-5500 3925);
FORCEPROP 1 LAST HDL_TAP TRUE
J 0
(-5175 3850);
DISPLAY 1.595745 (-5175 3850);
PAINT GREEN (-5175 3850);
DISPLAY INVISIBLE (-5175 3850);
FORCEPROP 1 LAST PATH I71
J 0
(-5502 3975);
DISPLAY 0.872340 (-5502 3975);
PAINT GREEN (-5502 3975);
DISPLAY INVISIBLE (-5502 3975);
FORCEADD OFFPAGE..6
(-6350 4800);
FORCEPROP 2 LAST $XR1 50 
J 0
(-6719 4800);
DISPLAY 0.638298 (-6719 4800);
PAINT MONO (-6719 4800);
FORCEPROP 2 LAST $XR0 49 
J 0
(-6629 4800);
DISPLAY 0.638298 (-6629 4800);
PAINT MONO (-6629 4800);
FORCEPROP 2 LAST CDS_LIB mstr_standard
J 0
(-6350 4800);
PAINT MONO (-6350 4800);
DISPLAY INVISIBLE (-6350 4800);
FORCEPROP 1 LAST OFFPAGE TRUE
J 0
(-6025 4675);
DISPLAY 1.170213 (-6025 4675);
PAINT GREEN (-6025 4675);
DISPLAY INVISIBLE (-6025 4675);
FORCEPROP 1 LAST COMMENT_BODY TRUE
J 0
(-6250 4725);
DISPLAY 1.170213 (-6250 4725);
PAINT GREEN (-6250 4725);
DISPLAY INVISIBLE (-6250 4725);
FORCEPROP 2 LAST PATH I72
J 0
(-6300 4875);
DISPLAY 1.021277 (-6300 4875);
PAINT ORANGE (-6300 4875);
DISPLAY INVISIBLE (-6300 4875);
FORCEADD TAP..6
(-5500 4025);
FORCEPROP 3 LASTPIN (-5450 4025) SIG_NAME M_D_DQ<50>
J 0
(-5440 4035);
DISPLAY 0.659574 (-5440 4035);
PAINT MONO (-5440 4035);
DISPLAY INVISIBLE (-5440 4035);
FORCEPROP 1 LASTPIN (-5450 4025) BN 50
J 0
(-5502 4033);
DISPLAY 0.617021 (-5502 4033);
PAINT PINK (-5502 4033);
FORCEPROP 2 LAST CDS_LIB mstr_standard
J 0
(-5500 4025);
PAINT MONO (-5500 4025);
DISPLAY INVISIBLE (-5500 4025);
FORCEPROP 1 LAST BODY_TYPE PLUMBING
J 0
(-5500 3975);
DISPLAY 1.595745 (-5500 3975);
PAINT GREEN (-5500 3975);
DISPLAY INVISIBLE (-5500 3975);
FORCEPROP 1 LAST HDL_TAP TRUE
J 0
(-5175 3900);
DISPLAY 1.595745 (-5175 3900);
PAINT GREEN (-5175 3900);
DISPLAY INVISIBLE (-5175 3900);
FORCEPROP 1 LAST PATH I73
J 0
(-5502 4025);
DISPLAY 0.872340 (-5502 4025);
PAINT GREEN (-5502 4025);
DISPLAY INVISIBLE (-5502 4025);
FORCEADD TAP..6
(-5500 4075);
FORCEPROP 3 LASTPIN (-5450 4075) SIG_NAME M_D_DQ<51>
J 0
(-5440 4085);
DISPLAY 0.659574 (-5440 4085);
PAINT MONO (-5440 4085);
DISPLAY INVISIBLE (-5440 4085);
FORCEPROP 1 LASTPIN (-5450 4075) BN 51
J 0
(-5502 4083);
DISPLAY 0.617021 (-5502 4083);
PAINT PINK (-5502 4083);
FORCEPROP 2 LAST CDS_LIB mstr_standard
J 0
(-5500 4075);
PAINT MONO (-5500 4075);
DISPLAY INVISIBLE (-5500 4075);
FORCEPROP 1 LAST BODY_TYPE PLUMBING
J 0
(-5500 4025);
DISPLAY 1.595745 (-5500 4025);
PAINT GREEN (-5500 4025);
DISPLAY INVISIBLE (-5500 4025);
FORCEPROP 1 LAST HDL_TAP TRUE
J 0
(-5175 3950);
DISPLAY 1.595745 (-5175 3950);
PAINT GREEN (-5175 3950);
DISPLAY INVISIBLE (-5175 3950);
FORCEPROP 1 LAST PATH I74
J 0
(-5502 4075);
DISPLAY 0.872340 (-5502 4075);
PAINT GREEN (-5502 4075);
DISPLAY INVISIBLE (-5502 4075);
FORCEADD TAP..6
(-5500 4125);
FORCEPROP 3 LASTPIN (-5450 4125) SIG_NAME M_D_DQ<52>
J 0
(-5440 4135);
DISPLAY 0.659574 (-5440 4135);
PAINT MONO (-5440 4135);
DISPLAY INVISIBLE (-5440 4135);
FORCEPROP 1 LASTPIN (-5450 4125) BN 52
J 0
(-5502 4133);
DISPLAY 0.617021 (-5502 4133);
PAINT PINK (-5502 4133);
FORCEPROP 2 LAST CDS_LIB mstr_standard
J 0
(-5500 4125);
PAINT MONO (-5500 4125);
DISPLAY INVISIBLE (-5500 4125);
FORCEPROP 1 LAST BODY_TYPE PLUMBING
J 0
(-5500 4075);
DISPLAY 1.595745 (-5500 4075);
PAINT GREEN (-5500 4075);
DISPLAY INVISIBLE (-5500 4075);
FORCEPROP 1 LAST HDL_TAP TRUE
J 0
(-5175 4000);
DISPLAY 1.595745 (-5175 4000);
PAINT GREEN (-5175 4000);
DISPLAY INVISIBLE (-5175 4000);
FORCEPROP 1 LAST PATH I75
J 0
(-5502 4125);
DISPLAY 0.872340 (-5502 4125);
PAINT GREEN (-5502 4125);
DISPLAY INVISIBLE (-5502 4125);
FORCEADD TAP..6
(-5500 4175);
FORCEPROP 3 LASTPIN (-5450 4175) SIG_NAME M_D_DQ<53>
J 0
(-5440 4185);
DISPLAY 0.659574 (-5440 4185);
PAINT MONO (-5440 4185);
DISPLAY INVISIBLE (-5440 4185);
FORCEPROP 1 LASTPIN (-5450 4175) BN 53
J 0
(-5502 4183);
DISPLAY 0.617021 (-5502 4183);
PAINT PINK (-5502 4183);
FORCEPROP 2 LAST CDS_LIB mstr_standard
J 0
(-5500 4175);
PAINT MONO (-5500 4175);
DISPLAY INVISIBLE (-5500 4175);
FORCEPROP 1 LAST BODY_TYPE PLUMBING
J 0
(-5500 4125);
DISPLAY 1.595745 (-5500 4125);
PAINT GREEN (-5500 4125);
DISPLAY INVISIBLE (-5500 4125);
FORCEPROP 1 LAST HDL_TAP TRUE
J 0
(-5175 4050);
DISPLAY 1.595745 (-5175 4050);
PAINT GREEN (-5175 4050);
DISPLAY INVISIBLE (-5175 4050);
FORCEPROP 1 LAST PATH I76
J 0
(-5502 4175);
DISPLAY 0.872340 (-5502 4175);
PAINT GREEN (-5502 4175);
DISPLAY INVISIBLE (-5502 4175);
FORCEADD TAP..6
(-5500 4225);
FORCEPROP 3 LASTPIN (-5450 4225) SIG_NAME M_D_DQ<54>
J 0
(-5440 4235);
DISPLAY 0.659574 (-5440 4235);
PAINT MONO (-5440 4235);
DISPLAY INVISIBLE (-5440 4235);
FORCEPROP 1 LASTPIN (-5450 4225) BN 54
J 0
(-5502 4233);
DISPLAY 0.617021 (-5502 4233);
PAINT PINK (-5502 4233);
FORCEPROP 2 LAST CDS_LIB mstr_standard
J 0
(-5500 4225);
PAINT MONO (-5500 4225);
DISPLAY INVISIBLE (-5500 4225);
FORCEPROP 1 LAST BODY_TYPE PLUMBING
J 0
(-5500 4175);
DISPLAY 1.595745 (-5500 4175);
PAINT GREEN (-5500 4175);
DISPLAY INVISIBLE (-5500 4175);
FORCEPROP 1 LAST HDL_TAP TRUE
J 0
(-5175 4100);
DISPLAY 1.595745 (-5175 4100);
PAINT GREEN (-5175 4100);
DISPLAY INVISIBLE (-5175 4100);
FORCEPROP 1 LAST PATH I77
J 0
(-5502 4225);
DISPLAY 0.872340 (-5502 4225);
PAINT GREEN (-5502 4225);
DISPLAY INVISIBLE (-5502 4225);
FORCEADD TAP..6
(-5500 4275);
FORCEPROP 3 LASTPIN (-5450 4275) SIG_NAME M_D_DQ<55>
J 0
(-5440 4285);
DISPLAY 0.659574 (-5440 4285);
PAINT MONO (-5440 4285);
DISPLAY INVISIBLE (-5440 4285);
FORCEPROP 1 LASTPIN (-5450 4275) BN 55
J 0
(-5502 4283);
DISPLAY 0.617021 (-5502 4283);
PAINT PINK (-5502 4283);
FORCEPROP 2 LAST CDS_LIB mstr_standard
J 0
(-5500 4275);
PAINT MONO (-5500 4275);
DISPLAY INVISIBLE (-5500 4275);
FORCEPROP 1 LAST BODY_TYPE PLUMBING
J 0
(-5500 4225);
DISPLAY 1.595745 (-5500 4225);
PAINT GREEN (-5500 4225);
DISPLAY INVISIBLE (-5500 4225);
FORCEPROP 1 LAST HDL_TAP TRUE
J 0
(-5175 4150);
DISPLAY 1.595745 (-5175 4150);
PAINT GREEN (-5175 4150);
DISPLAY INVISIBLE (-5175 4150);
FORCEPROP 1 LAST PATH I78
J 0
(-5502 4275);
DISPLAY 0.872340 (-5502 4275);
PAINT GREEN (-5502 4275);
DISPLAY INVISIBLE (-5502 4275);
FORCEADD TAP..6
(-5500 4325);
FORCEPROP 3 LASTPIN (-5450 4325) SIG_NAME M_D_DQ<56>
J 0
(-5440 4335);
DISPLAY 0.659574 (-5440 4335);
PAINT MONO (-5440 4335);
DISPLAY INVISIBLE (-5440 4335);
FORCEPROP 1 LASTPIN (-5450 4325) BN 56
J 0
(-5502 4333);
DISPLAY 0.617021 (-5502 4333);
PAINT PINK (-5502 4333);
FORCEPROP 2 LAST CDS_LIB mstr_standard
J 0
(-5500 4325);
PAINT MONO (-5500 4325);
DISPLAY INVISIBLE (-5500 4325);
FORCEPROP 1 LAST BODY_TYPE PLUMBING
J 0
(-5500 4275);
DISPLAY 1.595745 (-5500 4275);
PAINT GREEN (-5500 4275);
DISPLAY INVISIBLE (-5500 4275);
FORCEPROP 1 LAST HDL_TAP TRUE
J 0
(-5175 4200);
DISPLAY 1.595745 (-5175 4200);
PAINT GREEN (-5175 4200);
DISPLAY INVISIBLE (-5175 4200);
FORCEPROP 1 LAST PATH I79
J 0
(-5502 4325);
DISPLAY 0.872340 (-5502 4325);
PAINT GREEN (-5502 4325);
DISPLAY INVISIBLE (-5502 4325);
FORCEADD TAP..6
(-5500 725);
FORCEPROP 3 LASTPIN (-5450 725) SIG_NAME M_D_CLK_DN<2>
J 0
(-5440 735);
DISPLAY 0.659574 (-5440 735);
PAINT MONO (-5440 735);
DISPLAY INVISIBLE (-5440 735);
FORCEPROP 1 LASTPIN (-5450 725) BN 2
J 0
(-5502 733);
DISPLAY 0.617021 (-5502 733);
PAINT PINK (-5502 733);
FORCEPROP 2 LAST CDS_LIB mstr_standard
J 0
(-5500 725);
PAINT MONO (-5500 725);
DISPLAY INVISIBLE (-5500 725);
FORCEPROP 1 LAST BODY_TYPE PLUMBING
J 0
(-5500 675);
DISPLAY 1.595745 (-5500 675);
PAINT GREEN (-5500 675);
DISPLAY INVISIBLE (-5500 675);
FORCEPROP 1 LAST HDL_TAP TRUE
J 0
(-5175 600);
DISPLAY 1.595745 (-5175 600);
PAINT GREEN (-5175 600);
DISPLAY INVISIBLE (-5175 600);
FORCEPROP 1 LAST PATH I8
J 0
(-5502 725);
DISPLAY 0.872340 (-5502 725);
PAINT GREEN (-5502 725);
DISPLAY INVISIBLE (-5502 725);
FORCEADD TAP..6
(-5500 4375);
FORCEPROP 3 LASTPIN (-5450 4375) SIG_NAME M_D_DQ<57>
J 0
(-5440 4385);
DISPLAY 0.659574 (-5440 4385);
PAINT MONO (-5440 4385);
DISPLAY INVISIBLE (-5440 4385);
FORCEPROP 1 LASTPIN (-5450 4375) BN 57
J 0
(-5502 4383);
DISPLAY 0.617021 (-5502 4383);
PAINT PINK (-5502 4383);
FORCEPROP 2 LAST CDS_LIB mstr_standard
J 0
(-5500 4375);
PAINT MONO (-5500 4375);
DISPLAY INVISIBLE (-5500 4375);
FORCEPROP 1 LAST BODY_TYPE PLUMBING
J 0
(-5500 4325);
DISPLAY 1.595745 (-5500 4325);
PAINT GREEN (-5500 4325);
DISPLAY INVISIBLE (-5500 4325);
FORCEPROP 1 LAST HDL_TAP TRUE
J 0
(-5175 4250);
DISPLAY 1.595745 (-5175 4250);
PAINT GREEN (-5175 4250);
DISPLAY INVISIBLE (-5175 4250);
FORCEPROP 1 LAST PATH I80
J 0
(-5502 4375);
DISPLAY 0.872340 (-5502 4375);
PAINT GREEN (-5502 4375);
DISPLAY INVISIBLE (-5502 4375);
FORCEADD TAP..6
(-5500 4425);
FORCEPROP 3 LASTPIN (-5450 4425) SIG_NAME M_D_DQ<58>
J 0
(-5440 4435);
DISPLAY 0.659574 (-5440 4435);
PAINT MONO (-5440 4435);
DISPLAY INVISIBLE (-5440 4435);
FORCEPROP 1 LASTPIN (-5450 4425) BN 58
J 0
(-5502 4433);
DISPLAY 0.617021 (-5502 4433);
PAINT PINK (-5502 4433);
FORCEPROP 2 LAST CDS_LIB mstr_standard
J 0
(-5500 4425);
PAINT MONO (-5500 4425);
DISPLAY INVISIBLE (-5500 4425);
FORCEPROP 1 LAST BODY_TYPE PLUMBING
J 0
(-5500 4375);
DISPLAY 1.595745 (-5500 4375);
PAINT GREEN (-5500 4375);
DISPLAY INVISIBLE (-5500 4375);
FORCEPROP 1 LAST HDL_TAP TRUE
J 0
(-5175 4300);
DISPLAY 1.595745 (-5175 4300);
PAINT GREEN (-5175 4300);
DISPLAY INVISIBLE (-5175 4300);
FORCEPROP 1 LAST PATH I81
J 0
(-5502 4425);
DISPLAY 0.872340 (-5502 4425);
PAINT GREEN (-5502 4425);
DISPLAY INVISIBLE (-5502 4425);
FORCEADD TAP..6
(-5500 4475);
FORCEPROP 3 LASTPIN (-5450 4475) SIG_NAME M_D_DQ<59>
J 0
(-5440 4485);
DISPLAY 0.659574 (-5440 4485);
PAINT MONO (-5440 4485);
DISPLAY INVISIBLE (-5440 4485);
FORCEPROP 1 LASTPIN (-5450 4475) BN 59
J 0
(-5502 4483);
DISPLAY 0.617021 (-5502 4483);
PAINT PINK (-5502 4483);
FORCEPROP 2 LAST CDS_LIB mstr_standard
J 0
(-5500 4475);
PAINT MONO (-5500 4475);
DISPLAY INVISIBLE (-5500 4475);
FORCEPROP 1 LAST BODY_TYPE PLUMBING
J 0
(-5500 4425);
DISPLAY 1.595745 (-5500 4425);
PAINT GREEN (-5500 4425);
DISPLAY INVISIBLE (-5500 4425);
FORCEPROP 1 LAST HDL_TAP TRUE
J 0
(-5175 4350);
DISPLAY 1.595745 (-5175 4350);
PAINT GREEN (-5175 4350);
DISPLAY INVISIBLE (-5175 4350);
FORCEPROP 1 LAST PATH I82
J 0
(-5502 4475);
DISPLAY 0.872340 (-5502 4475);
PAINT GREEN (-5502 4475);
DISPLAY INVISIBLE (-5502 4475);
FORCEADD TAP..6
(-5500 4525);
FORCEPROP 3 LASTPIN (-5450 4525) SIG_NAME M_D_DQ<60>
J 0
(-5440 4535);
DISPLAY 0.659574 (-5440 4535);
PAINT MONO (-5440 4535);
DISPLAY INVISIBLE (-5440 4535);
FORCEPROP 1 LASTPIN (-5450 4525) BN 60
J 0
(-5502 4533);
DISPLAY 0.617021 (-5502 4533);
PAINT PINK (-5502 4533);
FORCEPROP 2 LAST CDS_LIB mstr_standard
J 0
(-5500 4525);
PAINT MONO (-5500 4525);
DISPLAY INVISIBLE (-5500 4525);
FORCEPROP 1 LAST BODY_TYPE PLUMBING
J 0
(-5500 4475);
DISPLAY 1.595745 (-5500 4475);
PAINT GREEN (-5500 4475);
DISPLAY INVISIBLE (-5500 4475);
FORCEPROP 1 LAST HDL_TAP TRUE
J 0
(-5175 4400);
DISPLAY 1.595745 (-5175 4400);
PAINT GREEN (-5175 4400);
DISPLAY INVISIBLE (-5175 4400);
FORCEPROP 1 LAST PATH I83
J 0
(-5502 4525);
DISPLAY 0.872340 (-5502 4525);
PAINT GREEN (-5502 4525);
DISPLAY INVISIBLE (-5502 4525);
FORCEADD TAP..6
(-5500 4575);
FORCEPROP 3 LASTPIN (-5450 4575) SIG_NAME M_D_DQ<61>
J 0
(-5440 4585);
DISPLAY 0.659574 (-5440 4585);
PAINT MONO (-5440 4585);
DISPLAY INVISIBLE (-5440 4585);
FORCEPROP 1 LASTPIN (-5450 4575) BN 61
J 0
(-5502 4583);
DISPLAY 0.617021 (-5502 4583);
PAINT PINK (-5502 4583);
FORCEPROP 2 LAST CDS_LIB mstr_standard
J 0
(-5500 4575);
PAINT MONO (-5500 4575);
DISPLAY INVISIBLE (-5500 4575);
FORCEPROP 1 LAST BODY_TYPE PLUMBING
J 0
(-5500 4525);
DISPLAY 1.595745 (-5500 4525);
PAINT GREEN (-5500 4525);
DISPLAY INVISIBLE (-5500 4525);
FORCEPROP 1 LAST HDL_TAP TRUE
J 0
(-5175 4450);
DISPLAY 1.595745 (-5175 4450);
PAINT GREEN (-5175 4450);
DISPLAY INVISIBLE (-5175 4450);
FORCEPROP 1 LAST PATH I84
J 0
(-5502 4575);
DISPLAY 0.872340 (-5502 4575);
PAINT GREEN (-5502 4575);
DISPLAY INVISIBLE (-5502 4575);
FORCEADD TAP..6
(-5500 4625);
FORCEPROP 3 LASTPIN (-5450 4625) SIG_NAME M_D_DQ<62>
J 0
(-5440 4635);
DISPLAY 0.659574 (-5440 4635);
PAINT MONO (-5440 4635);
DISPLAY INVISIBLE (-5440 4635);
FORCEPROP 1 LASTPIN (-5450 4625) BN 62
J 0
(-5502 4633);
DISPLAY 0.617021 (-5502 4633);
PAINT PINK (-5502 4633);
FORCEPROP 2 LAST CDS_LIB mstr_standard
J 0
(-5500 4625);
PAINT MONO (-5500 4625);
DISPLAY INVISIBLE (-5500 4625);
FORCEPROP 1 LAST BODY_TYPE PLUMBING
J 0
(-5500 4575);
DISPLAY 1.595745 (-5500 4575);
PAINT GREEN (-5500 4575);
DISPLAY INVISIBLE (-5500 4575);
FORCEPROP 1 LAST HDL_TAP TRUE
J 0
(-5175 4500);
DISPLAY 1.595745 (-5175 4500);
PAINT GREEN (-5175 4500);
DISPLAY INVISIBLE (-5175 4500);
FORCEPROP 1 LAST PATH I85
J 0
(-5502 4625);
DISPLAY 0.872340 (-5502 4625);
PAINT GREEN (-5502 4625);
DISPLAY INVISIBLE (-5502 4625);
FORCEADD TAP..6
(-5500 4675);
FORCEPROP 3 LASTPIN (-5450 4675) SIG_NAME M_D_DQ<63>
J 0
(-5440 4685);
DISPLAY 0.659574 (-5440 4685);
PAINT MONO (-5440 4685);
DISPLAY INVISIBLE (-5440 4685);
FORCEPROP 1 LASTPIN (-5450 4675) BN 63
J 0
(-5502 4683);
DISPLAY 0.617021 (-5502 4683);
PAINT PINK (-5502 4683);
FORCEPROP 2 LAST CDS_LIB mstr_standard
J 0
(-5500 4675);
PAINT MONO (-5500 4675);
DISPLAY INVISIBLE (-5500 4675);
FORCEPROP 1 LAST BODY_TYPE PLUMBING
J 0
(-5500 4625);
DISPLAY 1.595745 (-5500 4625);
PAINT GREEN (-5500 4625);
DISPLAY INVISIBLE (-5500 4625);
FORCEPROP 1 LAST HDL_TAP TRUE
J 0
(-5175 4550);
DISPLAY 1.595745 (-5175 4550);
PAINT GREEN (-5175 4550);
DISPLAY INVISIBLE (-5175 4550);
FORCEPROP 1 LAST PATH I86
J 0
(-5502 4675);
DISPLAY 0.872340 (-5502 4675);
PAINT GREEN (-5502 4675);
DISPLAY INVISIBLE (-5502 4675);
FORCEADD TAP..6
R 2
(-2775 725);
FORCEPROP 3 LASTPIN (-2825 725) SIG_NAME M_D_BA<0>
J 0
(-2815 735);
DISPLAY 0.659574 (-2815 735);
PAINT MONO (-2815 735);
DISPLAY INVISIBLE (-2815 735);
FORCEPROP 1 LASTPIN (-2825 725) BN 0
J 2
(-2773 733);
DISPLAY 0.617021 (-2773 733);
PAINT PINK (-2773 733);
FORCEPROP 2 LAST CDS_LIB mstr_standard
J 0
(-2775 725);
PAINT MONO (-2775 725);
DISPLAY INVISIBLE (-2775 725);
FORCEPROP 1 LAST BODY_TYPE PLUMBING
J 2
(-2775 675);
DISPLAY 1.595745 (-2775 675);
PAINT GREEN (-2775 675);
DISPLAY INVISIBLE (-2775 675);
FORCEPROP 1 LAST HDL_TAP TRUE
J 2
(-3100 600);
DISPLAY 1.595745 (-3100 600);
PAINT GREEN (-3100 600);
DISPLAY INVISIBLE (-3100 600);
FORCEPROP 1 LAST PATH I87
J 2
(-2773 725);
DISPLAY 0.872340 (-2773 725);
PAINT GREEN (-2773 725);
DISPLAY INVISIBLE (-2773 725);
FORCEADD TAP..6
R 2
(-2775 775);
FORCEPROP 3 LASTPIN (-2825 775) SIG_NAME M_D_BA<1>
J 0
(-2815 785);
DISPLAY 0.659574 (-2815 785);
PAINT MONO (-2815 785);
DISPLAY INVISIBLE (-2815 785);
FORCEPROP 1 LASTPIN (-2825 775) BN 1
J 2
(-2773 783);
DISPLAY 0.617021 (-2773 783);
PAINT PINK (-2773 783);
FORCEPROP 2 LAST CDS_LIB mstr_standard
J 0
(-2775 775);
PAINT MONO (-2775 775);
DISPLAY INVISIBLE (-2775 775);
FORCEPROP 1 LAST BODY_TYPE PLUMBING
J 2
(-2775 725);
DISPLAY 1.595745 (-2775 725);
PAINT GREEN (-2775 725);
DISPLAY INVISIBLE (-2775 725);
FORCEPROP 1 LAST HDL_TAP TRUE
J 2
(-3100 650);
DISPLAY 1.595745 (-3100 650);
PAINT GREEN (-3100 650);
DISPLAY INVISIBLE (-3100 650);
FORCEPROP 1 LAST PATH I88
J 2
(-2773 775);
DISPLAY 0.872340 (-2773 775);
PAINT GREEN (-2773 775);
DISPLAY INVISIBLE (-2773 775);
FORCEADD TAP..6
R 2
(-2775 875);
FORCEPROP 3 LASTPIN (-2825 875) SIG_NAME M_D_BG<1>
J 0
(-2815 885);
DISPLAY 0.659574 (-2815 885);
PAINT MONO (-2815 885);
DISPLAY INVISIBLE (-2815 885);
FORCEPROP 1 LASTPIN (-2825 875) BN 1
J 2
(-2773 883);
DISPLAY 0.617021 (-2773 883);
PAINT PINK (-2773 883);
FORCEPROP 2 LAST CDS_LIB mstr_standard
J 0
(-2775 875);
PAINT MONO (-2775 875);
DISPLAY INVISIBLE (-2775 875);
FORCEPROP 1 LAST BODY_TYPE PLUMBING
J 2
(-2775 825);
DISPLAY 1.595745 (-2775 825);
PAINT GREEN (-2775 825);
DISPLAY INVISIBLE (-2775 825);
FORCEPROP 1 LAST HDL_TAP TRUE
J 2
(-3100 750);
DISPLAY 1.595745 (-3100 750);
PAINT GREEN (-3100 750);
DISPLAY INVISIBLE (-3100 750);
FORCEPROP 1 LAST PATH I89
J 2
(-2773 875);
DISPLAY 0.872340 (-2773 875);
PAINT GREEN (-2773 875);
DISPLAY INVISIBLE (-2773 875);
FORCEADD TAP..6
(-5500 825);
FORCEPROP 3 LASTPIN (-5450 825) SIG_NAME M_D_CLK_DP<0>
J 0
(-5440 835);
DISPLAY 0.659574 (-5440 835);
PAINT MONO (-5440 835);
DISPLAY INVISIBLE (-5440 835);
FORCEPROP 1 LASTPIN (-5450 825) BN 0
J 0
(-5502 833);
DISPLAY 0.617021 (-5502 833);
PAINT PINK (-5502 833);
FORCEPROP 2 LAST CDS_LIB mstr_standard
J 0
(-5500 825);
PAINT MONO (-5500 825);
DISPLAY INVISIBLE (-5500 825);
FORCEPROP 1 LAST BODY_TYPE PLUMBING
J 0
(-5500 775);
DISPLAY 1.595745 (-5500 775);
PAINT GREEN (-5500 775);
DISPLAY INVISIBLE (-5500 775);
FORCEPROP 1 LAST HDL_TAP TRUE
J 0
(-5175 700);
DISPLAY 1.595745 (-5175 700);
PAINT GREEN (-5175 700);
DISPLAY INVISIBLE (-5175 700);
FORCEPROP 1 LAST PATH I9
J 0
(-5502 825);
DISPLAY 0.872340 (-5502 825);
PAINT GREEN (-5502 825);
DISPLAY INVISIBLE (-5502 825);
FORCEADD TAP..6
R 2
(-2775 825);
FORCEPROP 3 LASTPIN (-2825 825) SIG_NAME M_D_BG<0>
J 0
(-2815 835);
DISPLAY 0.659574 (-2815 835);
PAINT MONO (-2815 835);
DISPLAY INVISIBLE (-2815 835);
FORCEPROP 1 LASTPIN (-2825 825) BN 0
J 2
(-2773 833);
DISPLAY 0.617021 (-2773 833);
PAINT PINK (-2773 833);
FORCEPROP 2 LAST CDS_LIB mstr_standard
J 0
(-2775 825);
PAINT MONO (-2775 825);
DISPLAY INVISIBLE (-2775 825);
FORCEPROP 1 LAST BODY_TYPE PLUMBING
J 2
(-2775 775);
DISPLAY 1.595745 (-2775 775);
PAINT GREEN (-2775 775);
DISPLAY INVISIBLE (-2775 775);
FORCEPROP 1 LAST HDL_TAP TRUE
J 2
(-3100 700);
DISPLAY 1.595745 (-3100 700);
PAINT GREEN (-3100 700);
DISPLAY INVISIBLE (-3100 700);
FORCEPROP 1 LAST PATH I90
J 2
(-2773 825);
DISPLAY 0.872340 (-2773 825);
PAINT GREEN (-2773 825);
DISPLAY INVISIBLE (-2773 825);
FORCEADD TAP..6
R 2
(-2775 1025);
FORCEPROP 3 LASTPIN (-2825 1025) SIG_NAME M_D_CS_N<1>
J 0
(-2815 1035);
DISPLAY 0.659574 (-2815 1035);
PAINT MONO (-2815 1035);
DISPLAY INVISIBLE (-2815 1035);
FORCEPROP 1 LASTPIN (-2825 1025) BN 1
J 2
(-2773 1033);
DISPLAY 0.617021 (-2773 1033);
PAINT PINK (-2773 1033);
FORCEPROP 2 LAST CDS_LIB mstr_standard
J 0
(-2775 1025);
PAINT MONO (-2775 1025);
DISPLAY INVISIBLE (-2775 1025);
FORCEPROP 1 LAST BODY_TYPE PLUMBING
J 2
(-2775 975);
DISPLAY 1.595745 (-2775 975);
PAINT GREEN (-2775 975);
DISPLAY INVISIBLE (-2775 975);
FORCEPROP 1 LAST HDL_TAP TRUE
J 2
(-3100 900);
DISPLAY 1.595745 (-3100 900);
PAINT GREEN (-3100 900);
DISPLAY INVISIBLE (-3100 900);
FORCEPROP 1 LAST PATH I91
J 2
(-2773 1025);
DISPLAY 0.872340 (-2773 1025);
PAINT GREEN (-2773 1025);
DISPLAY INVISIBLE (-2773 1025);
FORCEADD TAP..6
R 2
(-2775 975);
FORCEPROP 3 LASTPIN (-2825 975) SIG_NAME M_D_CS_N<0>
J 0
(-2815 985);
DISPLAY 0.659574 (-2815 985);
PAINT MONO (-2815 985);
DISPLAY INVISIBLE (-2815 985);
FORCEPROP 1 LASTPIN (-2825 975) BN 0
J 2
(-2773 983);
DISPLAY 0.617021 (-2773 983);
PAINT PINK (-2773 983);
FORCEPROP 2 LAST CDS_LIB mstr_standard
J 0
(-2775 975);
PAINT MONO (-2775 975);
DISPLAY INVISIBLE (-2775 975);
FORCEPROP 1 LAST BODY_TYPE PLUMBING
J 2
(-2775 925);
DISPLAY 1.595745 (-2775 925);
PAINT GREEN (-2775 925);
DISPLAY INVISIBLE (-2775 925);
FORCEPROP 1 LAST HDL_TAP TRUE
J 2
(-3100 850);
DISPLAY 1.595745 (-3100 850);
PAINT GREEN (-3100 850);
DISPLAY INVISIBLE (-3100 850);
FORCEPROP 1 LAST PATH I92
J 2
(-2773 975);
DISPLAY 0.872340 (-2773 975);
PAINT GREEN (-2773 975);
DISPLAY INVISIBLE (-2773 975);
FORCEADD TAP..6
R 2
(-2775 1075);
FORCEPROP 3 LASTPIN (-2825 1075) SIG_NAME M_D_CS_N<2>
J 0
(-2815 1085);
DISPLAY 0.659574 (-2815 1085);
PAINT MONO (-2815 1085);
DISPLAY INVISIBLE (-2815 1085);
FORCEPROP 1 LASTPIN (-2825 1075) BN 2
J 2
(-2773 1083);
DISPLAY 0.617021 (-2773 1083);
PAINT PINK (-2773 1083);
FORCEPROP 2 LAST CDS_LIB mstr_standard
J 0
(-2775 1075);
PAINT MONO (-2775 1075);
DISPLAY INVISIBLE (-2775 1075);
FORCEPROP 1 LAST BODY_TYPE PLUMBING
J 2
(-2775 1025);
DISPLAY 1.595745 (-2775 1025);
PAINT GREEN (-2775 1025);
DISPLAY INVISIBLE (-2775 1025);
FORCEPROP 1 LAST HDL_TAP TRUE
J 2
(-3100 950);
DISPLAY 1.595745 (-3100 950);
PAINT GREEN (-3100 950);
DISPLAY INVISIBLE (-3100 950);
FORCEPROP 1 LAST PATH I93
J 2
(-2773 1075);
DISPLAY 0.872340 (-2773 1075);
PAINT GREEN (-2773 1075);
DISPLAY INVISIBLE (-2773 1075);
FORCEADD TAP..6
R 2
(-2775 1175);
FORCEPROP 3 LASTPIN (-2825 1175) SIG_NAME M_D_CS_N<4>
J 0
(-2815 1185);
DISPLAY 0.659574 (-2815 1185);
PAINT MONO (-2815 1185);
DISPLAY INVISIBLE (-2815 1185);
FORCEPROP 1 LASTPIN (-2825 1175) BN 4
J 2
(-2773 1183);
DISPLAY 0.617021 (-2773 1183);
PAINT PINK (-2773 1183);
FORCEPROP 2 LAST CDS_LIB mstr_standard
J 0
(-2775 1175);
PAINT MONO (-2775 1175);
DISPLAY INVISIBLE (-2775 1175);
FORCEPROP 1 LAST BODY_TYPE PLUMBING
J 2
(-2775 1125);
DISPLAY 1.595745 (-2775 1125);
PAINT GREEN (-2775 1125);
DISPLAY INVISIBLE (-2775 1125);
FORCEPROP 1 LAST HDL_TAP TRUE
J 2
(-3100 1050);
DISPLAY 1.595745 (-3100 1050);
PAINT GREEN (-3100 1050);
DISPLAY INVISIBLE (-3100 1050);
FORCEPROP 1 LAST PATH I94
J 2
(-2773 1175);
DISPLAY 0.872340 (-2773 1175);
PAINT GREEN (-2773 1175);
DISPLAY INVISIBLE (-2773 1175);
FORCEADD TAP..6
R 2
(-2775 1125);
FORCEPROP 3 LASTPIN (-2825 1125) SIG_NAME M_D_CS_N<3>
J 0
(-2815 1135);
DISPLAY 0.659574 (-2815 1135);
PAINT MONO (-2815 1135);
DISPLAY INVISIBLE (-2815 1135);
FORCEPROP 1 LASTPIN (-2825 1125) BN 3
J 2
(-2773 1133);
DISPLAY 0.617021 (-2773 1133);
PAINT PINK (-2773 1133);
FORCEPROP 2 LAST CDS_LIB mstr_standard
J 0
(-2775 1125);
PAINT MONO (-2775 1125);
DISPLAY INVISIBLE (-2775 1125);
FORCEPROP 1 LAST BODY_TYPE PLUMBING
J 2
(-2775 1075);
DISPLAY 1.595745 (-2775 1075);
PAINT GREEN (-2775 1075);
DISPLAY INVISIBLE (-2775 1075);
FORCEPROP 1 LAST HDL_TAP TRUE
J 2
(-3100 1000);
DISPLAY 1.595745 (-3100 1000);
PAINT GREEN (-3100 1000);
DISPLAY INVISIBLE (-3100 1000);
FORCEPROP 1 LAST PATH I95
J 2
(-2773 1125);
DISPLAY 0.872340 (-2773 1125);
PAINT GREEN (-2773 1125);
DISPLAY INVISIBLE (-2773 1125);
FORCEADD TAP..6
R 2
(-2775 1325);
FORCEPROP 3 LASTPIN (-2825 1325) SIG_NAME M_D_CS_N<7>
J 0
(-2815 1335);
DISPLAY 0.659574 (-2815 1335);
PAINT MONO (-2815 1335);
DISPLAY INVISIBLE (-2815 1335);
FORCEPROP 1 LASTPIN (-2825 1325) BN 7
J 2
(-2773 1333);
DISPLAY 0.617021 (-2773 1333);
PAINT PINK (-2773 1333);
FORCEPROP 2 LAST CDS_LIB mstr_standard
J 0
(-2775 1325);
PAINT MONO (-2775 1325);
DISPLAY INVISIBLE (-2775 1325);
FORCEPROP 1 LAST BODY_TYPE PLUMBING
J 2
(-2775 1275);
DISPLAY 1.595745 (-2775 1275);
PAINT GREEN (-2775 1275);
DISPLAY INVISIBLE (-2775 1275);
FORCEPROP 1 LAST HDL_TAP TRUE
J 2
(-3100 1200);
DISPLAY 1.595745 (-3100 1200);
PAINT GREEN (-3100 1200);
DISPLAY INVISIBLE (-3100 1200);
FORCEPROP 1 LAST PATH I96
J 2
(-2773 1325);
DISPLAY 0.872340 (-2773 1325);
PAINT GREEN (-2773 1325);
DISPLAY INVISIBLE (-2773 1325);
FORCEADD TAP..6
R 2
(-2775 1225);
FORCEPROP 3 LASTPIN (-2825 1225) SIG_NAME M_D_CS_N<5>
J 0
(-2815 1235);
DISPLAY 0.659574 (-2815 1235);
PAINT MONO (-2815 1235);
DISPLAY INVISIBLE (-2815 1235);
FORCEPROP 1 LASTPIN (-2825 1225) BN 5
J 2
(-2773 1233);
DISPLAY 0.617021 (-2773 1233);
PAINT PINK (-2773 1233);
FORCEPROP 2 LAST CDS_LIB mstr_standard
J 0
(-2775 1225);
PAINT MONO (-2775 1225);
DISPLAY INVISIBLE (-2775 1225);
FORCEPROP 1 LAST BODY_TYPE PLUMBING
J 2
(-2775 1175);
DISPLAY 1.595745 (-2775 1175);
PAINT GREEN (-2775 1175);
DISPLAY INVISIBLE (-2775 1175);
FORCEPROP 1 LAST HDL_TAP TRUE
J 2
(-3100 1100);
DISPLAY 1.595745 (-3100 1100);
PAINT GREEN (-3100 1100);
DISPLAY INVISIBLE (-3100 1100);
FORCEPROP 1 LAST PATH I97
J 2
(-2773 1225);
DISPLAY 0.872340 (-2773 1225);
PAINT GREEN (-2773 1225);
DISPLAY INVISIBLE (-2773 1225);
FORCEADD TAP..6
R 2
(-2775 1275);
FORCEPROP 3 LASTPIN (-2825 1275) SIG_NAME M_D_CS_N<6>
J 0
(-2815 1285);
DISPLAY 0.659574 (-2815 1285);
PAINT MONO (-2815 1285);
DISPLAY INVISIBLE (-2815 1285);
FORCEPROP 1 LASTPIN (-2825 1275) BN 6
J 2
(-2773 1283);
DISPLAY 0.617021 (-2773 1283);
PAINT PINK (-2773 1283);
FORCEPROP 2 LAST CDS_LIB mstr_standard
J 0
(-2775 1275);
PAINT MONO (-2775 1275);
DISPLAY INVISIBLE (-2775 1275);
FORCEPROP 1 LAST BODY_TYPE PLUMBING
J 2
(-2775 1225);
DISPLAY 1.595745 (-2775 1225);
PAINT GREEN (-2775 1225);
DISPLAY INVISIBLE (-2775 1225);
FORCEPROP 1 LAST HDL_TAP TRUE
J 2
(-3100 1150);
DISPLAY 1.595745 (-3100 1150);
PAINT GREEN (-3100 1150);
DISPLAY INVISIBLE (-3100 1150);
FORCEPROP 1 LAST PATH I98
J 2
(-2773 1275);
DISPLAY 0.872340 (-2773 1275);
PAINT GREEN (-2773 1275);
DISPLAY INVISIBLE (-2773 1275);
FORCEADD TAP..6
R 2
(-2775 1425);
FORCEPROP 3 LASTPIN (-2825 1425) SIG_NAME M_D_ODT<0>
J 0
(-2815 1435);
DISPLAY 0.659574 (-2815 1435);
PAINT MONO (-2815 1435);
DISPLAY INVISIBLE (-2815 1435);
FORCEPROP 1 LASTPIN (-2825 1425) BN 0
J 2
(-2773 1433);
DISPLAY 0.617021 (-2773 1433);
PAINT PINK (-2773 1433);
FORCEPROP 2 LAST CDS_LIB mstr_standard
J 0
(-2775 1425);
PAINT MONO (-2775 1425);
DISPLAY INVISIBLE (-2775 1425);
FORCEPROP 1 LAST BODY_TYPE PLUMBING
J 2
(-2775 1375);
DISPLAY 1.595745 (-2775 1375);
PAINT GREEN (-2775 1375);
DISPLAY INVISIBLE (-2775 1375);
FORCEPROP 1 LAST HDL_TAP TRUE
J 2
(-3100 1300);
DISPLAY 1.595745 (-3100 1300);
PAINT GREEN (-3100 1300);
DISPLAY INVISIBLE (-3100 1300);
FORCEPROP 1 LAST PATH I99
J 2
(-2773 1425);
DISPLAY 0.872340 (-2773 1425);
PAINT GREEN (-2773 1425);
DISPLAY INVISIBLE (-2773 1425);
FORCEADD INTEL_CORP_BPAGE..1
(0 0);
FORCEPROP 1 LAST CDS_CON_LAST_MODIFIED Fri Jun 16 17:48:11 2017
J 0
(-1425 325);
DISPLAY 1.340426 (-1425 325);
PAINT GREEN (-1425 325);
DISPLAY INVISIBLE (-1425 325);
FORCEPROP 1 LAST CUSTOM_TXT_CDS <CURRENT_DESIGN_SHEET> OF <TOTAL_DESIGN_SHEETS>
J 0
(-500 25);
PAINT ORANGE (-500 25);
FORCEPROP 1 LAST CUSTOM_TXT_CDS <CON_LAST_MODIFIED>
J 0
(-4000 100);
PAINT ORANGE (-4000 100);
FORCEPROP 2 LAST CUSTOM_TXT_CDS <XR_PAGE_TITLE>
J 0
(-7890 5250);
DISPLAY 0.638298 (-7890 5250);
PAINT PINK (-7890 5250);
DISPLAY INVISIBLE (-7890 5250);
FORCEPROP 1 LAST SCH_TITLE SKYLAKE - SKT0 - 6 OF 21
J 0
(-7950 50);
DISPLAY 1.212766 (-7950 50);
PAINT GREEN (-7950 50);
FORCEPROP 2 LAST CDS_LIB mstr_symbols
J 0
(0 0);
PAINT ORANGE (0 0);
DISPLAY INVISIBLE (0 0);
FORCEPROP 2 LAST PAGE_BORDER TRUE
J 0
(-7890 5250);
DISPLAY 0.851064 (-7890 5250);
PAINT PINK (-7890 5250);
DISPLAY INVISIBLE (-7890 5250);
FORCEPROP 1 LAST COMMENT_BODY TRUE
J 0
(12 12);
DISPLAY 0.638298 (12 12);
PAINT GREEN (12 12);
DISPLAY INVISIBLE (12 12);
FORCEPROP 2 LAST CDS_XR_PAGE_TITLE CR-26 : @BASEBOARD_FAB2_LIB.BASEBOARD_FAB2(SCH_1):PAGE26
J 0
(-7890 5250);
DISPLAY 0.638298 (-7890 5250);
PAINT PINK (-7890 5250);
DISPLAY INVISIBLE (-7890 5250);
FORCEADD DESIGN_NOTE..1
(-6525 400);
FORCEPROP 0 LAST L1 CPU SYMBOLS 1-30 ARE PRELIMINARY AND SUBJECT TO CHANGE
J 0
(-6725 275);
DISPLAY 1.021277 (-6725 275);
PAINT ORANGE (-6725 275);
FORCEPROP 2 LAST CDS_LIB mstr_symbols
J 0
(-6525 400);
PAINT ORANGE (-6525 400);
DISPLAY INVISIBLE (-6525 400);
FORCEPROP 1 LAST COMMENT_BODY TRUE
J 0
(-6500 500);
DISPLAY 0.978723 (-6500 500);
PAINT ORANGE (-6500 500);
DISPLAY INVISIBLE (-6500 500);
FORCEADD PRELIM..10
(-4140 2565);
PAINT GRAY (-4140 2565);
FORCEPROP 2 LAST CDS_LIB mstr_misc
J 0
(-4140 2565);
PAINT ORANGE (-4140 2565);
DISPLAY INVISIBLE (-4140 2565);
FORCEPROP 1 LAST COMMENT_BODY TRUE
J 0
(-4140 2565);
PAINT ORANGE (-4140 2565);
DISPLAY INVISIBLE (-4140 2565);
WIRE 17 -1 (-2725 3850)(-2725 3900);
WIRE 17 -1 (-2725 3900)(-2725 3950);
WIRE 17 -1 (-2725 3950)(-2725 4000);
WIRE 17 -1 (-2725 4000)(-2725 4050);
WIRE 17 -1 (-2725 4050)(-2725 4100);
WIRE 17 -1 (-2725 4100)(-2725 4150);
WIRE 17 -1 (-2725 4150)(-2725 4200);
WIRE 17 -1 (-2725 4200)(-2725 4250);
WIRE 17 -1 (-2725 4250)(-2725 4300);
WIRE 17 -1 (-2725 4300)(-2725 4350);
WIRE 17 -1 (-2725 4350)(-2725 4400);
WIRE 17 -1 (-2725 4400)(-2725 4450);
WIRE 17 -1 (-1975 4750)(-2725 4750);
FORCEPROP 2 LAST SIG_NAME M_D_DQS_DP<17:0>
J 0
(-2625 4760);
DISPLAY 0.617021 (-2625 4760);
PAINT ORANGE (-2625 4760);
WIRE 17 -1 (-2725 4450)(-2725 4500);
WIRE 17 -1 (-2725 4500)(-2725 4550);
WIRE 17 -1 (-2725 4700)(-2725 4750);
WIRE 17 -1 (-2725 4650)(-2725 4700);
WIRE 17 -1 (-2725 4550)(-2725 4600);
WIRE 17 -1 (-2725 4600)(-2725 4650);
WIRE 17 -1 (-2725 2900)(-2725 2950);
WIRE 17 -1 (-2725 2950)(-2725 3000);
WIRE 17 -1 (-2725 3000)(-2725 3050);
WIRE 17 -1 (-2725 3050)(-2725 3100);
WIRE 17 -1 (-2725 3100)(-2725 3150);
WIRE 17 -1 (-2725 3150)(-2725 3200);
WIRE 17 -1 (-2725 3200)(-2725 3250);
WIRE 17 -1 (-2725 3250)(-2725 3300);
WIRE 17 -1 (-2725 3300)(-2725 3350);
WIRE 17 -1 (-2725 3350)(-2725 3400);
WIRE 17 -1 (-2725 3400)(-2725 3450);
WIRE 17 -1 (-2725 3450)(-2725 3500);
WIRE 17 -1 (-2725 3500)(-2725 3550);
WIRE 17 -1 (-2725 3550)(-2725 3600);
WIRE 17 -1 (-2725 3600)(-2725 3650);
WIRE 17 -1 (-2725 3650)(-2725 3700);
WIRE 17 -1 (-1975 3775)(-2725 3775);
FORCEPROP 2 LAST SIG_NAME M_D_DQS_DN<17:0>
J 0
(-2625 3785);
DISPLAY 0.617021 (-2625 3785);
PAINT ORANGE (-2625 3785);
WIRE 17 -1 (-2725 3700)(-2725 3750);
WIRE 17 -1 (-2725 3750)(-2725 3775);
WIRE 17 -1 (-2725 1950)(-2725 2000);
WIRE 17 -1 (-2725 2000)(-2725 2050);
WIRE 17 -1 (-2725 2050)(-2725 2100);
WIRE 17 -1 (-2725 2100)(-2725 2150);
WIRE 17 -1 (-2725 2150)(-2725 2200);
WIRE 17 -1 (-2725 2200)(-2725 2250);
WIRE 17 -1 (-2725 2250)(-2725 2300);
WIRE 17 -1 (-2725 2300)(-2725 2350);
WIRE 17 -1 (-2725 2350)(-2725 2400);
WIRE 17 -1 (-2725 2400)(-2725 2450);
WIRE 17 -1 (-2725 2450)(-2725 2500);
WIRE 17 -1 (-2725 2500)(-2725 2550);
WIRE 17 -1 (-2725 2550)(-2725 2600);
WIRE 17 -1 (-2725 2600)(-2725 2650);
WIRE 17 -1 (-2725 2650)(-2725 2700);
WIRE 17 -1 (-2725 2700)(-2725 2750);
WIRE 17 -1 (-1975 2825)(-2725 2825);
FORCEPROP 2 LAST SIG_NAME M_D_MA<17:0>
J 0
(-2625 2835);
DISPLAY 0.617021 (-2625 2835);
PAINT ORANGE (-2625 2835);
WIRE 17 -1 (-2725 2750)(-2725 2800);
WIRE 17 -1 (-2725 2800)(-2725 2825);
WIRE 17 -1 (-1975 825)(-2725 825);
FORCEPROP 2 LAST SIG_NAME M_D_BA<1:0>
J 0
(-2625 835);
DISPLAY 0.617021 (-2625 835);
PAINT ORANGE (-2625 835);
WIRE 17 -1 (-2725 750)(-2725 800);
WIRE 17 -1 (-2725 800)(-2725 825);
WIRE 17 -1 (-1975 925)(-2725 925);
FORCEPROP 2 LAST SIG_NAME M_D_BG<1:0>
J 0
(-2625 935);
DISPLAY 0.617021 (-2625 935);
PAINT ORANGE (-2625 935);
WIRE 17 -1 (-2725 850)(-2725 900);
WIRE 17 -1 (-2725 900)(-2725 925);
WIRE 17 -1 (-2725 1700)(-2725 1750);
WIRE 17 -1 (-2725 1750)(-2725 1800);
WIRE 17 -1 (-1975 1875)(-2725 1875);
FORCEPROP 2 LAST SIG_NAME M_D_CKE<3:0>
J 0
(-2625 1885);
DISPLAY 0.617021 (-2625 1885);
PAINT ORANGE (-2625 1885);
WIRE 17 -1 (-2725 1800)(-2725 1850);
WIRE 17 -1 (-2725 1850)(-2725 1875);
WIRE 17 -1 (-2725 1000)(-2725 1050);
WIRE 17 -1 (-2725 1050)(-2725 1100);
WIRE 17 -1 (-2725 1100)(-2725 1150);
WIRE 17 -1 (-2725 1150)(-2725 1200);
WIRE 17 -1 (-2725 1200)(-2725 1250);
WIRE 17 -1 (-2725 1250)(-2725 1300);
WIRE 17 -1 (-1975 1375)(-2725 1375);
FORCEPROP 2 LAST SIG_NAME M_D_CS_N<7:0>
J 0
(-2625 1385);
DISPLAY 0.617021 (-2625 1385);
PAINT ORANGE (-2625 1385);
WIRE 17 -1 (-2725 1300)(-2725 1350);
WIRE 17 -1 (-2725 1350)(-2725 1375);
WIRE 17 -1 (-2725 1450)(-2725 1500);
WIRE 17 -1 (-2725 1500)(-2725 1550);
WIRE 17 -1 (-1975 1625)(-2725 1625);
FORCEPROP 2 LAST SIG_NAME M_D_ODT<3:0>
J 0
(-2625 1635);
DISPLAY 0.617021 (-2625 1635);
PAINT ORANGE (-2625 1635);
WIRE 17 -1 (-2725 1550)(-2725 1600);
WIRE 17 -1 (-2725 1600)(-2725 1625);
WIRE 17 -1 (-5550 1550)(-5550 1600);
WIRE 17 -1 (-5550 1600)(-5550 1650);
WIRE 17 -1 (-5550 1650)(-5550 1700);
WIRE 17 -1 (-5550 1700)(-5550 1750);
WIRE 17 -1 (-5550 1750)(-5550 1800);
WIRE 17 -1 (-5550 1800)(-5550 1850);
WIRE 17 -1 (-5550 1850)(-5550 1900);
WIRE 17 -1 (-5550 1900)(-5550 1950);
WIRE 17 -1 (-5550 1950)(-5550 2000);
WIRE 17 -1 (-5550 2000)(-5550 2050);
WIRE 17 -1 (-5550 2050)(-5550 2100);
WIRE 17 -1 (-5550 2100)(-5550 2150);
WIRE 17 -1 (-5550 2150)(-5550 2200);
WIRE 17 -1 (-5550 2200)(-5550 2250);
WIRE 17 -1 (-5550 2250)(-5550 2300);
WIRE 17 -1 (-5550 2300)(-5550 2350);
WIRE 17 -1 (-5550 2350)(-5550 2400);
WIRE 17 -1 (-5550 2400)(-5550 2450);
WIRE 17 -1 (-5550 2450)(-5550 2500);
WIRE 17 -1 (-5550 2500)(-5550 2550);
WIRE 17 -1 (-5550 2550)(-5550 2600);
WIRE 17 -1 (-5550 2600)(-5550 2650);
WIRE 17 -1 (-5550 2650)(-5550 2700);
WIRE 17 -1 (-5550 2700)(-5550 2750);
WIRE 17 -1 (-5550 2750)(-5550 2800);
WIRE 17 -1 (-5550 2800)(-5550 2850);
WIRE 17 -1 (-5550 2850)(-5550 2900);
WIRE 17 -1 (-5550 2900)(-5550 2950);
WIRE 17 -1 (-5550 2950)(-5550 3000);
WIRE 17 -1 (-5550 3000)(-5550 3050);
WIRE 17 -1 (-5550 3050)(-5550 3100);
WIRE 17 -1 (-5550 3100)(-5550 3150);
WIRE 17 -1 (-5550 3150)(-5550 3200);
WIRE 17 -1 (-5550 3200)(-5550 3250);
WIRE 17 -1 (-5550 3250)(-5550 3300);
WIRE 17 -1 (-5550 3300)(-5550 3350);
WIRE 17 -1 (-5550 3350)(-5550 3400);
WIRE 17 -1 (-5550 3400)(-5550 3450);
WIRE 17 -1 (-5550 3450)(-5550 3500);
WIRE 17 -1 (-5550 3500)(-5550 3550);
WIRE 17 -1 (-5550 3550)(-5550 3600);
WIRE 17 -1 (-5550 3600)(-5550 3650);
WIRE 17 -1 (-5550 3650)(-5550 3700);
WIRE 17 -1 (-5550 3700)(-5550 3750);
WIRE 17 -1 (-5550 3750)(-5550 3800);
WIRE 17 -1 (-5550 3800)(-5550 3850);
WIRE 17 -1 (-5550 3850)(-5550 3900);
WIRE 17 -1 (-5550 3900)(-5550 3950);
WIRE 17 -1 (-5550 3950)(-5550 4000);
WIRE 17 -1 (-5550 4000)(-5550 4050);
WIRE 17 -1 (-5550 4050)(-5550 4100);
WIRE 17 -1 (-5550 4100)(-5550 4150);
WIRE 17 -1 (-5550 4150)(-5550 4200);
WIRE 17 -1 (-5550 4200)(-5550 4250);
WIRE 17 -1 (-5550 4250)(-5550 4300);
WIRE 17 -1 (-5550 4300)(-5550 4350);
WIRE 17 -1 (-5550 4350)(-5550 4400);
WIRE 17 -1 (-5550 4400)(-5550 4450);
WIRE 17 -1 (-5550 4450)(-5550 4500);
WIRE 17 -1 (-5550 4500)(-5550 4550);
WIRE 17 -1 (-5550 4550)(-5550 4600);
WIRE 17 -1 (-5550 4800)(-6300 4800);
FORCEPROP 2 LAST SIG_NAME M_D_DQ<63:0>
J 0
(-6250 4810);
DISPLAY 0.617021 (-6250 4810);
PAINT ORANGE (-6250 4810);
WIRE 17 -1 (-5550 4700)(-5550 4800);
WIRE 17 -1 (-5550 4600)(-5550 4650);
WIRE 17 -1 (-5550 4650)(-5550 4700);
WIRE 17 -1 (-5550 650)(-5550 700);
WIRE 17 -1 (-5550 700)(-5550 750);
WIRE 17 -1 (-5550 825)(-6300 825);
FORCEPROP 2 LAST SIG_NAME M_D_CLK_DN<3:0>
J 0
(-6250 835);
DISPLAY 0.617021 (-6250 835);
PAINT ORANGE (-6250 835);
WIRE 17 -1 (-5550 750)(-5550 800);
WIRE 17 -1 (-5550 800)(-5550 825);
WIRE 17 -1 (-5550 850)(-5550 900);
WIRE 17 -1 (-5550 900)(-5550 950);
WIRE 17 -1 (-5550 1025)(-6300 1025);
FORCEPROP 2 LAST SIG_NAME M_D_CLK_DP<3:0>
J 0
(-6250 1035);
DISPLAY 0.617021 (-6250 1035);
PAINT ORANGE (-6250 1035);
WIRE 17 -1 (-5550 950)(-5550 1000);
WIRE 17 -1 (-5550 1000)(-5550 1025);
WIRE 17 -1 (-5550 1100)(-5550 1150);
WIRE 17 -1 (-5550 1150)(-5550 1200);
WIRE 17 -1 (-5550 1200)(-5550 1250);
WIRE 17 -1 (-5550 1250)(-5550 1300);
WIRE 17 -1 (-5550 1300)(-5550 1350);
WIRE 17 -1 (-5550 1350)(-5550 1400);
WIRE 17 -1 (-5550 1475)(-6300 1475);
FORCEPROP 2 LAST SIG_NAME M_D_ECC<7:0>
J 0
(-6250 1485);
DISPLAY 0.617021 (-6250 1485);
PAINT ORANGE (-6250 1485);
WIRE 17 -1 (-5550 1400)(-5550 1450);
WIRE 17 -1 (-5550 1450)(-5550 1475);
WIRE 16 -1 (-3250 3225)(-2825 3225);
WIRE 16 -1 (-4950 4275)(-5450 4275);
WIRE 16 -1 (-4950 1125)(-5450 1125);
WIRE 16 -1 (-5450 3575)(-4950 3575);
WIRE 16 -1 (-3250 3925)(-2825 3925);
WIRE 16 -1 (-5450 2925)(-4950 2925);
WIRE 16 -1 (-4950 4125)(-5450 4125);
WIRE 16 -1 (-4950 3025)(-5450 3025);
WIRE 16 -1 (-3250 1525)(-2825 1525);
WIRE 16 -1 (-5450 3225)(-4950 3225);
WIRE 16 -1 (-5450 3125)(-4950 3125);
WIRE 16 -1 (-3250 4675)(-2825 4675);
WIRE 16 -1 (-3250 525)(-1975 525);
FORCEPROP 2 LAST SIG_NAME M_D_PAR
J 0
(-2625 535);
DISPLAY 0.617021 (-2625 535);
PAINT ORANGE (-2625 535);
WIRE 16 -1 (-5450 2975)(-4950 2975);
WIRE 16 -1 (-5450 1775)(-4950 1775);
WIRE 16 -1 (-4950 525)(-6300 525);
FORCEPROP 2 LAST SIG_NAME M_D_C<2>
J 0
(-6250 535);
DISPLAY 0.617021 (-6250 535);
PAINT ORANGE (-6250 535);
WIRE 16 -1 (-4950 1075)(-5450 1075);
WIRE 16 -1 (-4950 1175)(-5450 1175);
WIRE 16 -1 (-4950 1225)(-5450 1225);
WIRE 16 -1 (-4950 1275)(-5450 1275);
WIRE 16 -1 (-4950 1325)(-5450 1325);
WIRE 16 -1 (-4950 1375)(-5450 1375);
WIRE 16 -1 (-4950 1425)(-5450 1425);
WIRE 16 -1 (-5450 1525)(-4950 1525);
WIRE 16 -1 (-5450 1575)(-4950 1575);
WIRE 16 -1 (-5450 1625)(-4950 1625);
WIRE 16 -1 (-4950 1675)(-5450 1675);
WIRE 16 -1 (-5450 1725)(-4950 1725);
WIRE 16 -1 (-4950 1825)(-5450 1825);
WIRE 16 -1 (-5450 1875)(-4950 1875);
WIRE 16 -1 (-5450 1925)(-4950 1925);
WIRE 16 -1 (-5450 1975)(-4950 1975);
WIRE 16 -1 (-5450 2025)(-4950 2025);
WIRE 16 -1 (-4950 825)(-5450 825);
WIRE 16 -1 (-4950 875)(-5450 875);
WIRE 16 -1 (-4950 925)(-5450 925);
WIRE 16 -1 (-4950 975)(-5450 975);
WIRE 16 -1 (-4950 625)(-5450 625);
WIRE 16 -1 (-4950 675)(-5450 675);
WIRE 16 -1 (-4950 725)(-5450 725);
WIRE 16 -1 (-4950 775)(-5450 775);
WIRE 16 -1 (-5450 2075)(-4950 2075);
WIRE 16 -1 (-5450 2125)(-4950 2125);
WIRE 16 -1 (-5450 2175)(-4950 2175);
WIRE 16 -1 (-5450 2225)(-4950 2225);
WIRE 16 -1 (-4950 2275)(-5450 2275);
WIRE 16 -1 (-5450 2325)(-4950 2325);
WIRE 16 -1 (-5450 2375)(-4950 2375);
WIRE 16 -1 (-4950 2425)(-5450 2425);
WIRE 16 -1 (-5450 2475)(-4950 2475);
WIRE 16 -1 (-5450 2525)(-4950 2525);
WIRE 16 -1 (-5450 2575)(-4950 2575);
WIRE 16 -1 (-5450 2625)(-4950 2625);
WIRE 16 -1 (-4950 2675)(-5450 2675);
WIRE 16 -1 (-5450 2725)(-4950 2725);
WIRE 16 -1 (-5450 2775)(-4950 2775);
WIRE 16 -1 (-5450 2825)(-4950 2825);
WIRE 16 -1 (-5450 2875)(-4950 2875);
WIRE 16 -1 (-5450 3075)(-4950 3075);
WIRE 16 -1 (-5450 3175)(-4950 3175);
WIRE 16 -1 (-5450 3275)(-4950 3275);
WIRE 16 -1 (-5450 3325)(-4950 3325);
WIRE 16 -1 (-4950 3375)(-5450 3375);
WIRE 16 -1 (-5450 3425)(-4950 3425);
WIRE 16 -1 (-5450 3475)(-4950 3475);
WIRE 16 -1 (-4950 3525)(-5450 3525);
WIRE 16 -1 (-5450 3625)(-4950 3625);
WIRE 16 -1 (-4950 3675)(-5450 3675);
WIRE 16 -1 (-4950 3725)(-5450 3725);
WIRE 16 -1 (-4950 3775)(-5450 3775);
WIRE 16 -1 (-4950 3825)(-5450 3825);
WIRE 16 -1 (-4950 3875)(-5450 3875);
WIRE 16 -1 (-4950 3925)(-5450 3925);
WIRE 16 -1 (-4950 3975)(-5450 3975);
WIRE 16 -1 (-4950 4025)(-5450 4025);
WIRE 16 -1 (-4950 4075)(-5450 4075);
WIRE 16 -1 (-4950 4175)(-5450 4175);
WIRE 16 -1 (-4950 4225)(-5450 4225);
WIRE 16 -1 (-4950 4325)(-5450 4325);
WIRE 16 -1 (-4950 4375)(-5450 4375);
WIRE 16 -1 (-4950 4425)(-5450 4425);
WIRE 16 -1 (-4950 4475)(-5450 4475);
WIRE 16 -1 (-4950 4525)(-5450 4525);
WIRE 16 -1 (-4950 4575)(-5450 4575);
WIRE 16 -1 (-4950 4625)(-5450 4625);
WIRE 16 -1 (-4950 4675)(-5450 4675);
WIRE 16 -1 (-3250 1425)(-2825 1425);
WIRE 16 -1 (-3250 1475)(-2825 1475);
WIRE 16 -1 (-3250 1575)(-2825 1575);
WIRE 16 -1 (-3250 1925)(-2825 1925);
WIRE 16 -1 (-3250 1975)(-2825 1975);
WIRE 16 -1 (-3250 2025)(-2825 2025);
WIRE 16 -1 (-3250 975)(-2825 975);
WIRE 16 -1 (-3250 1025)(-2825 1025);
WIRE 16 -1 (-3250 1075)(-2825 1075);
WIRE 16 -1 (-3250 1125)(-2825 1125);
WIRE 16 -1 (-3250 1175)(-2825 1175);
WIRE 16 -1 (-3250 1225)(-2825 1225);
WIRE 16 -1 (-3250 1275)(-2825 1275);
WIRE 16 -1 (-3250 1325)(-2825 1325);
WIRE 16 -1 (-3250 1675)(-2825 1675);
WIRE 16 -1 (-3250 1725)(-2825 1725);
WIRE 16 -1 (-3250 1775)(-2825 1775);
WIRE 16 -1 (-3250 1825)(-2825 1825);
WIRE 16 -1 (-3250 825)(-2825 825);
WIRE 16 -1 (-3250 875)(-2825 875);
WIRE 16 -1 (-3250 725)(-2825 725);
WIRE 16 -1 (-3250 775)(-2825 775);
WIRE 16 -1 (-3250 2075)(-2825 2075);
WIRE 16 -1 (-3250 2125)(-2825 2125);
WIRE 16 -1 (-3250 2175)(-2825 2175);
WIRE 16 -1 (-3250 2225)(-2825 2225);
WIRE 16 -1 (-3250 2275)(-2825 2275);
WIRE 16 -1 (-3250 2325)(-2825 2325);
WIRE 16 -1 (-3250 2375)(-2825 2375);
WIRE 16 -1 (-3250 2425)(-2825 2425);
WIRE 16 -1 (-3250 2475)(-2825 2475);
WIRE 16 -1 (-3250 2525)(-2825 2525);
WIRE 16 -1 (-3250 2575)(-2825 2575);
WIRE 16 -1 (-3250 2625)(-2825 2625);
WIRE 16 -1 (-3250 2675)(-2825 2675);
WIRE 16 -1 (-3250 2725)(-2825 2725);
WIRE 16 -1 (-3250 2775)(-2825 2775);
WIRE 16 -1 (-3250 3825)(-2825 3825);
WIRE 16 -1 (-3250 3875)(-2825 3875);
WIRE 16 -1 (-3250 3975)(-2825 3975);
WIRE 16 -1 (-3250 4025)(-2825 4025);
WIRE 16 -1 (-3250 4075)(-2825 4075);
WIRE 16 -1 (-3250 2875)(-2825 2875);
WIRE 16 -1 (-3250 2925)(-2825 2925);
WIRE 16 -1 (-3250 2975)(-2825 2975);
WIRE 16 -1 (-3250 3025)(-2825 3025);
WIRE 16 -1 (-3250 3075)(-2825 3075);
WIRE 16 -1 (-3250 3125)(-2825 3125);
WIRE 16 -1 (-3250 3175)(-2825 3175);
WIRE 16 -1 (-3250 3275)(-2825 3275);
WIRE 16 -1 (-3250 3325)(-2825 3325);
WIRE 16 -1 (-3250 3375)(-2825 3375);
WIRE 16 -1 (-3250 3425)(-2825 3425);
WIRE 16 -1 (-3250 3475)(-2825 3475);
WIRE 16 -1 (-3250 3525)(-2825 3525);
WIRE 16 -1 (-3250 3575)(-2825 3575);
WIRE 16 -1 (-3250 3625)(-2825 3625);
WIRE 16 -1 (-3250 3675)(-2825 3675);
WIRE 16 -1 (-3250 3725)(-2825 3725);
WIRE 16 -1 (-3250 575)(-1975 575);
FORCEPROP 2 LAST SIG_NAME M_D_ALERT_N
J 0
(-2625 585);
DISPLAY 0.617021 (-2625 585);
PAINT ORANGE (-2625 585);
WIRE 16 -1 (-3250 625)(-1975 625);
FORCEPROP 2 LAST SIG_NAME M_D_ACT_N
J 0
(-2625 635);
DISPLAY 0.617021 (-2625 635);
PAINT ORANGE (-2625 635);
WIRE 16 -1 (-3250 4125)(-2825 4125);
WIRE 16 -1 (-3250 4175)(-2825 4175);
WIRE 16 -1 (-3250 4225)(-2825 4225);
WIRE 16 -1 (-3250 4275)(-2825 4275);
WIRE 16 -1 (-3250 4325)(-2825 4325);
WIRE 16 -1 (-3250 4375)(-2825 4375);
WIRE 16 -1 (-3250 4425)(-2825 4425);
WIRE 16 -1 (-3250 4475)(-2825 4475);
WIRE 16 -1 (-3250 4525)(-2825 4525);
WIRE 16 -1 (-3250 4575)(-2825 4575);
WIRE 16 -1 (-3250 4625)(-2825 4625);
FORCENOTE
SKYLAKE - SKT0 - 6 OF 21
(-1675 150) 0;
DISPLAY LEFT (-1675 150);
DISPLAY 1.021277 (-1675 150);
PAINT RED (-1675 150);
FORCENOTE
ROOM=CPU0
(-7975 375) 0;
DISPLAY LEFT (-7975 375);
DISPLAY 1.382979 (-7975 375);
PAINT PURPLE (-7975 375);
FORCENOTE
BOM_COST=PROC_SOCKET
(-7975 250) 0;
DISPLAY LEFT (-7975 250);
DISPLAY 1.382979 (-7975 250);
PAINT PURPLE (-7975 250);
QUIT
